FILE_TYPE = MACRO_DRAWING;
SET COLOR_WIRE YELLOW;
SET COLOR_PROP ORANGE;
SET COLOR_DOT WHITE;
SET COLOR_ARC YELLOW;
SET COLOR_BODY GREEN;
SET COLOR_NOTE PURPLE;
SET PROP_DISPLAY VALUE;
SET PAGE_NUMBER P151;
FORCEADD OFFPAGE..1
(-5700 1950);
FORCEPROP 2 LAST $XR2 154 
J 0
(-6222 1950);
DISPLAY 0.638298 (-6222 1950);
PAINT MONO (-6222 1950);
FORCEPROP 2 LAST $XR1 158 
J 0
(-6102 1950);
DISPLAY 0.638298 (-6102 1950);
PAINT MONO (-6102 1950);
FORCEPROP 2 LAST $XR0 153 
J 0
(-5982 1950);
DISPLAY 0.638298 (-5982 1950);
PAINT MONO (-5982 1950);
FORCEPROP 2 LAST PATH I1
J 0
(-5975 2000);
DISPLAY 1.021277 (-5975 2000);
DISPLAY INVISIBLE (-5975 2000);
FORCEPROP 2 LAST CDS_LIB standard
J 0
(-5700 1950);
PAINT MONO (-5700 1950);
DISPLAY INVISIBLE (-5700 1950);
FORCEPROP 1 LAST COMMENT_BODY TRUE
J 0
(-5575 1850);
DISPLAY 0.872340 (-5575 1850);
PAINT GREEN (-5575 1850);
DISPLAY INVISIBLE (-5575 1850);
FORCEPROP 1 LAST OFFPAGE TRUE
J 0
(-5375 1825);
DISPLAY 0.872340 (-5375 1825);
PAINT GREEN (-5375 1825);
DISPLAY INVISIBLE (-5375 1825);
FORCEADD OFFPAGE..1
(-4300 3775);
FORCEPROP 2 LAST $XR1 213 
J 0
(-4672 3775);
DISPLAY 0.638298 (-4672 3775);
PAINT MONO (-4672 3775);
FORCEPROP 2 LAST $XR0 153 
J 0
(-4552 3775);
DISPLAY 0.638298 (-4552 3775);
PAINT MONO (-4552 3775);
FORCEPROP 2 LAST PATH I10
J 0
(-4875 3825);
DISPLAY 1.021277 (-4875 3825);
DISPLAY INVISIBLE (-4875 3825);
FORCEPROP 2 LAST CDS_LIB standard
J 0
(-4300 3775);
PAINT MONO (-4300 3775);
DISPLAY INVISIBLE (-4300 3775);
FORCEPROP 1 LAST COMMENT_BODY TRUE
J 0
(-4175 3675);
DISPLAY 0.872340 (-4175 3675);
PAINT GREEN (-4175 3675);
DISPLAY INVISIBLE (-4175 3675);
FORCEPROP 1 LAST OFFPAGE TRUE
J 0
(-3975 3650);
DISPLAY 0.872340 (-3975 3650);
PAINT GREEN (-3975 3650);
DISPLAY INVISIBLE (-3975 3650);
FORCEADD UNIVERSAL_GND..1
(-3375 1625);
FORCEPROP 3 LASTPIN (-3375 1675) SIG_NAME GND\g
J 0
(-3365 1685);
DISPLAY 0.659574 (-3365 1685);
PAINT MONO (-3365 1685);
DISPLAY INVISIBLE (-3365 1685);
FORCEPROP 1 LAST PATH I11
J 0
(-3300 1625);
DISPLAY 0.872340 (-3300 1625);
PAINT AQUA (-3300 1625);
DISPLAY INVISIBLE (-3300 1625);
FORCEPROP 2 LAST CDS_LIB logical_power
J 0
(-3375 1625);
PAINT MONO (-3375 1625);
DISPLAY INVISIBLE (-3375 1625);
FORCEPROP 1 LAST HDL_POWER GND
J 1
(-3350 1550);
DISPLAY 0.872340 (-3350 1550);
PAINT GREEN (-3350 1550);
DISPLAY INVISIBLE (-3350 1550);
FORCEADD UNIVERSAL_GND..1
(-2525 1550);
FORCEPROP 3 LASTPIN (-2525 1600) SIG_NAME GND\g
J 0
(-2515 1610);
DISPLAY 0.659574 (-2515 1610);
PAINT MONO (-2515 1610);
DISPLAY INVISIBLE (-2515 1610);
FORCEPROP 1 LAST PATH I12
J 0
(-2450 1550);
DISPLAY 0.872340 (-2450 1550);
PAINT AQUA (-2450 1550);
DISPLAY INVISIBLE (-2450 1550);
FORCEPROP 2 LAST CDS_LIB logical_power
J 0
(-2525 1550);
PAINT MONO (-2525 1550);
DISPLAY INVISIBLE (-2525 1550);
FORCEPROP 1 LAST HDL_POWER GND
J 1
(-2500 1475);
DISPLAY 0.872340 (-2500 1475);
PAINT GREEN (-2500 1475);
DISPLAY INVISIBLE (-2500 1475);
FORCEADD Q_RES..2
(-2525 1775);
FORCEPROP 1 LAST PART_NUMBER CS41002FB09
J 0
(-2485 1650);
DISPLAY 0.638298 (-2485 1650);
DISPLAY INVISIBLE (-2485 1650);
FORCEPROP 1 LAST PACK_TYPE 0402LF
J 0
(-2485 1600);
DISPLAY 0.638298 (-2485 1600);
FORCEPROP 1 LAST TOLERANCE 1%
J 0
(-2480 1800);
DISPLAY 0.638298 (-2480 1800);
FORCEPROP 1 LAST WATTAGE 1/16W
J 0
(-2485 1750);
DISPLAY 0.638298 (-2485 1750);
FORCEPROP 1 LAST MATERIAL CHIP
J 0
(-2485 1700);
DISPLAY 0.638298 (-2485 1700);
FORCEPROP 1 LAST VALUE 100K
J 0
(-2480 1850);
DISPLAY 0.638298 (-2480 1850);
FORCEPROP 1 LAST $LOCATION R3232
J 0
(-2480 1900);
DISPLAY 0.787234 (-2480 1900);
FORCEPROP 1 LASTPIN (-2525 1875) $PN 1
J 0
(-2520 1837);
DISPLAY 0.787234 (-2520 1837);
FORCEPROP 1 LASTPIN (-2525 1675) $PN 2
J 0
(-2520 1685);
DISPLAY 0.787234 (-2520 1685);
FORCEPROP 1 LAST PATH I13
J 0
(-2475 1950);
DISPLAY 0.978723 (-2475 1950);
PAINT WHITE (-2475 1950);
DISPLAY INVISIBLE (-2475 1950);
FORCEPROP 2 LAST CDS_LIB pure_quanta
J 0
(-2525 1775);
PAINT MONO (-2525 1775);
DISPLAY INVISIBLE (-2525 1775);
FORCEPROP 2 LAST CDS_LOCATION R3232
J 0
(-2475 2000);
DISPLAY 1.021277 (-2475 2000);
DISPLAY INVISIBLE (-2475 2000);
FORCEPROP 2 LAST $SEC 1
J 0
(-2475 2000);
DISPLAY 0.680851 (-2475 2000);
PAINT MONO (-2475 2000);
DISPLAY INVISIBLE (-2475 2000);
FORCEPROP 2 LAST CDS_SEC 1
J 0
(-2475 2000);
DISPLAY 1.021277 (-2475 2000);
DISPLAY INVISIBLE (-2475 2000);
FORCEADD OFFPAGE..1
(-3200 3200);
FORCEPROP 2 LAST $XR0 215 
J 0
(-3452 3200);
DISPLAY 0.638298 (-3452 3200);
PAINT MONO (-3452 3200);
FORCEPROP 2 LAST PATH I14
J 0
(-3450 3250);
DISPLAY 1.021277 (-3450 3250);
DISPLAY INVISIBLE (-3450 3250);
FORCEPROP 1 LAST COMMENT_BODY TRUE
J 0
(-3075 3100);
DISPLAY 0.872340 (-3075 3100);
PAINT GREEN (-3075 3100);
DISPLAY INVISIBLE (-3075 3100);
FORCEPROP 1 LAST OFFPAGE TRUE
J 0
(-2875 3075);
DISPLAY 0.872340 (-2875 3075);
PAINT GREEN (-2875 3075);
DISPLAY INVISIBLE (-2875 3075);
FORCEPROP 2 LAST CDS_LIB standard
J 0
(-3200 3200);
DISPLAY INVISIBLE (-3200 3200);
FORCEADD 74LVC1G126SE7..1
(-3050 3725);
FORCEPROP 1 LAST PART_NUMBER AL1G0126009
J 0
(-2944 3409);
DISPLAY 0.723404 (-2944 3409);
PAINT GREEN (-2944 3409);
DISPLAY INVISIBLE (-2944 3409);
FORCEPROP 2 LAST PART_TYPE SMLF
J 0
(-2925 3900);
DISPLAY 0.638298 (-2925 3900);
FORCEPROP 1 LAST MATERIAL IC
J 0
(-2944 3282);
DISPLAY 0.723404 (-2944 3282);
PAINT GREEN (-2944 3282);
FORCEPROP 2 LAST VALUE 74LVC1G126SE-7
J 0
(-2925 3850);
DISPLAY 0.638298 (-2925 3850);
FORCEPROP 1 LAST LOCATION U66
J 0
(-2944 3556);
DISPLAY 0.723404 (-2944 3556);
PAINT GREEN (-2944 3556);
FORCEPROP 2 LASTPIN (-3300 3775) $PN 2
J 2
(-3310 3785);
DISPLAY 0.680851 (-3310 3785);
PAINT MONO (-3310 3785);
FORCEPROP 2 LASTPIN (-3050 3475) $PN 3
R 1
J 2
(-3060 3465);
DISPLAY 0.680851 (-3060 3465);
PAINT MONO (-3060 3465);
FORCEPROP 2 LASTPIN (-3300 3675) $PN 1
J 2
(-3310 3685);
DISPLAY 0.680851 (-3310 3685);
PAINT MONO (-3310 3685);
FORCEPROP 2 LASTPIN (-3050 3975) $PN 5
R 1
J 0
(-3060 3985);
DISPLAY 0.680851 (-3060 3985);
PAINT MONO (-3060 3985);
FORCEPROP 2 LASTPIN (-2800 3725) $PN 4
J 0
(-2790 3735);
DISPLAY 0.680851 (-2790 3735);
PAINT MONO (-2790 3735);
FORCEPROP 1 LAST PATH I15
J 0
(-3050 3725);
DISPLAY 0.723404 (-3050 3725);
PAINT GREEN (-3050 3725);
DISPLAY INVISIBLE (-3050 3725);
FORCEPROP 1 LAST NEEDS_NO_SIZE TRUE
J 0
(-3050 3725);
DISPLAY 0.723404 (-3050 3725);
PAINT GREEN (-3050 3725);
DISPLAY INVISIBLE (-3050 3725);
FORCEPROP 2 LAST SEC_TYPE 
J 0
(-2925 3950);
DISPLAY 1.021277 (-2925 3950);
DISPLAY INVISIBLE (-2925 3950);
FORCEPROP 1 LAST CDS_LMAN_SYM_OUTLINE -100,100,100,-100
J 0
(-3050 3725);
DISPLAY 0.468085 (-3050 3725);
PAINT GREEN (-3050 3725);
DISPLAY INVISIBLE (-3050 3725);
FORCEPROP 2 LAST CDS_LIB pure_quanta
J 0
(-3050 3725);
DISPLAY INVISIBLE (-3050 3725);
FORCEPROP 2 LAST SEC 1
J 0
(-2925 3950);
DISPLAY 0.680851 (-2925 3950);
PAINT MONO (-2925 3950);
DISPLAY INVISIBLE (-2925 3950);
FORCEADD UNIVERSAL_GND..1
(-3050 3350);
FORCEPROP 3 LASTPIN (-3050 3400) SIG_NAME GND\g
J 0
(-3040 3410);
DISPLAY 0.659574 (-3040 3410);
PAINT MONO (-3040 3410);
DISPLAY INVISIBLE (-3040 3410);
FORCEPROP 1 LAST PATH I16
J 0
(-2975 3350);
DISPLAY 0.872340 (-2975 3350);
PAINT AQUA (-2975 3350);
DISPLAY INVISIBLE (-2975 3350);
FORCEPROP 2 LAST CDS_LIB logical_power
J 0
(-3050 3350);
PAINT MONO (-3050 3350);
DISPLAY INVISIBLE (-3050 3350);
FORCEPROP 1 LAST HDL_POWER GND
J 1
(-3025 3275);
DISPLAY 0.872340 (-3025 3275);
PAINT GREEN (-3025 3275);
DISPLAY INVISIBLE (-3025 3275);
FORCEADD Q_RES..1
(-2200 2000);
FORCEPROP 1 LAST PART_NUMBER CS00002JB13
J 0
(-2300 2050);
DISPLAY 0.510638 (-2300 2050);
DISPLAY INVISIBLE (-2300 2050);
FORCEPROP 1 LAST PACK_TYPE 0402LF
J 0
(-2300 2100);
DISPLAY 0.510638 (-2300 2100);
FORCEPROP 1 LAST MATERIAL CHIP
J 0
(-1975 2000);
DISPLAY 0.510638 (-1975 2000);
FORCEPROP 1 LAST VALUE 0
J 2
(-2075 2000);
DISPLAY 0.510638 (-2075 2000);
FORCEPROP 1 LAST TOLERANCE 5%
J 0
(-2050 2000);
DISPLAY 0.510638 (-2050 2000);
FORCEPROP 1 LAST WATTAGE 1/16W
J 2
(-1950 2100);
DISPLAY 0.510638 (-1950 2100);
FORCEPROP 1 LAST $LOCATION R3233
J 0
(-2425 2000);
DISPLAY 0.787234 (-2425 2000);
FORCEPROP 1 LASTPIN (-2300 2000) $PN 1
J 0
(-2288 2012);
DISPLAY 0.787234 (-2288 2012);
PAINT MONO (-2288 2012);
FORCEPROP 1 LASTPIN (-2100 2000) $PN 2
J 0
(-2138 2012);
DISPLAY 0.787234 (-2138 2012);
PAINT MONO (-2138 2012);
FORCEPROP 1 LAST PATH I17
J 0
(-2250 2150);
DISPLAY 0.978723 (-2250 2150);
PAINT WHITE (-2250 2150);
DISPLAY INVISIBLE (-2250 2150);
FORCEPROP 2 LAST CDS_LIB pure_quanta
J 0
(-2200 2000);
DISPLAY INVISIBLE (-2200 2000);
FORCEPROP 0 LAST CDS_LOCATION R3233
J 0
(-1950 2125);
DISPLAY 1.021277 (-1950 2125);
DISPLAY INVISIBLE (-1950 2125);
FORCEPROP 0 LAST $SEC 1
J 0
(-1950 2125);
DISPLAY 0.680851 (-1950 2125);
PAINT MONO (-1950 2125);
DISPLAY INVISIBLE (-1950 2125);
FORCEPROP 0 LAST CDS_SEC 1
J 0
(-1950 2125);
DISPLAY 1.021277 (-1950 2125);
DISPLAY INVISIBLE (-1950 2125);
FORCEADD Q_RES..1
(-1900 3200);
FORCEPROP 1 LAST PART_NUMBER CS00002JB13
J 0
(-2000 3250);
DISPLAY 0.510638 (-2000 3250);
DISPLAY INVISIBLE (-2000 3250);
FORCEPROP 1 LAST VALUE 0
J 2
(-1775 3200);
DISPLAY 0.510638 (-1775 3200);
FORCEPROP 1 LAST TOLERANCE 5%
J 0
(-1750 3200);
DISPLAY 0.510638 (-1750 3200);
FORCEPROP 1 LAST WATTAGE 1/16W
J 2
(-1650 3300);
DISPLAY 0.510638 (-1650 3300);
FORCEPROP 1 LAST MATERIAL EMPTY
J 0
(-1675 3200);
DISPLAY 0.510638 (-1675 3200);
PAINT RED (-1675 3200);
FORCEPROP 1 LAST PACK_TYPE 0402LF
J 0
(-2000 3300);
DISPLAY 0.510638 (-2000 3300);
FORCEPROP 1 LAST $LOCATION R2474
J 0
(-2125 3200);
DISPLAY 0.787234 (-2125 3200);
FORCEPROP 1 LASTPIN (-2000 3200) $PN 1
J 0
(-1988 3212);
DISPLAY 0.787234 (-1988 3212);
PAINT MONO (-1988 3212);
FORCEPROP 1 LASTPIN (-1800 3200) $PN 2
J 0
(-1838 3212);
DISPLAY 0.787234 (-1838 3212);
PAINT MONO (-1838 3212);
FORCEPROP 1 LAST PATH I19
J 0
(-1950 3350);
DISPLAY 0.978723 (-1950 3350);
PAINT WHITE (-1950 3350);
DISPLAY INVISIBLE (-1950 3350);
FORCEPROP 2 LAST CDS_LIB pure_quanta
J 0
(-1900 3200);
DISPLAY INVISIBLE (-1900 3200);
FORCEPROP 0 LAST CDS_LOCATION R2474
J 0
(-1650 3325);
DISPLAY 1.021277 (-1650 3325);
DISPLAY INVISIBLE (-1650 3325);
FORCEPROP 0 LAST $SEC 1
J 0
(-1650 3325);
DISPLAY 0.680851 (-1650 3325);
PAINT MONO (-1650 3325);
DISPLAY INVISIBLE (-1650 3325);
FORCEPROP 0 LAST CDS_SEC 1
J 0
(-1650 3325);
DISPLAY 1.021277 (-1650 3325);
DISPLAY INVISIBLE (-1650 3325);
FORCEADD OFFPAGE..1
(-5900 3675);
FORCEPROP 2 LAST $XR2 154 
J 0
(-6392 3675);
DISPLAY 0.638298 (-6392 3675);
PAINT MONO (-6392 3675);
FORCEPROP 2 LAST $XR1 158 
J 0
(-6272 3675);
DISPLAY 0.638298 (-6272 3675);
PAINT MONO (-6272 3675);
FORCEPROP 2 LAST $XR0 153 
J 0
(-6152 3675);
DISPLAY 0.638298 (-6152 3675);
PAINT MONO (-6152 3675);
FORCEPROP 2 LAST PATH I2
J 0
(-6150 3725);
DISPLAY 1.021277 (-6150 3725);
DISPLAY INVISIBLE (-6150 3725);
FORCEPROP 1 LAST OFFPAGE TRUE
J 0
(-5575 3550);
DISPLAY 0.872340 (-5575 3550);
PAINT GREEN (-5575 3550);
DISPLAY INVISIBLE (-5575 3550);
FORCEPROP 1 LAST COMMENT_BODY TRUE
J 0
(-5775 3575);
DISPLAY 0.872340 (-5775 3575);
PAINT GREEN (-5775 3575);
DISPLAY INVISIBLE (-5775 3575);
FORCEPROP 2 LAST CDS_LIB standard
J 0
(-5900 3675);
PAINT MONO (-5900 3675);
DISPLAY INVISIBLE (-5900 3675);
FORCEADD UNIVERSAL_GND..1
(-1475 3300);
FORCEPROP 3 LASTPIN (-1475 3350) SIG_NAME GND\g
J 0
(-1465 3360);
DISPLAY 0.659574 (-1465 3360);
PAINT MONO (-1465 3360);
DISPLAY INVISIBLE (-1465 3360);
FORCEPROP 1 LAST PATH I20
J 0
(-1400 3300);
DISPLAY 0.872340 (-1400 3300);
PAINT AQUA (-1400 3300);
DISPLAY INVISIBLE (-1400 3300);
FORCEPROP 1 LAST HDL_POWER GND
J 1
(-1450 3225);
DISPLAY 0.872340 (-1450 3225);
PAINT GREEN (-1450 3225);
DISPLAY INVISIBLE (-1450 3225);
FORCEPROP 2 LAST CDS_LIB logical_power
J 0
(-1475 3300);
PAINT MONO (-1475 3300);
DISPLAY INVISIBLE (-1475 3300);
FORCEADD Q_RES..2
(-1475 3525);
FORCEPROP 1 LAST PART_NUMBER CS41002FB09
J 0
(-1435 3400);
DISPLAY 0.638298 (-1435 3400);
DISPLAY INVISIBLE (-1435 3400);
FORCEPROP 1 LAST MATERIAL CHIP
J 0
(-1435 3450);
DISPLAY 0.638298 (-1435 3450);
FORCEPROP 1 LAST PACK_TYPE 0402LF
J 0
(-1435 3350);
DISPLAY 0.638298 (-1435 3350);
FORCEPROP 1 LAST VALUE 100K
J 0
(-1430 3600);
DISPLAY 0.638298 (-1430 3600);
FORCEPROP 1 LAST TOLERANCE 1%
J 0
(-1430 3550);
DISPLAY 0.638298 (-1430 3550);
FORCEPROP 1 LAST WATTAGE 1/16W
J 0
(-1435 3500);
DISPLAY 0.638298 (-1435 3500);
FORCEPROP 1 LAST $LOCATION R1289
J 0
(-1430 3650);
DISPLAY 0.787234 (-1430 3650);
FORCEPROP 1 LASTPIN (-1475 3625) $PN 1
J 0
(-1470 3587);
DISPLAY 0.787234 (-1470 3587);
FORCEPROP 1 LASTPIN (-1475 3425) $PN 2
J 0
(-1470 3435);
DISPLAY 0.787234 (-1470 3435);
FORCEPROP 1 LAST PATH I21
J 0
(-1425 3700);
DISPLAY 0.978723 (-1425 3700);
PAINT WHITE (-1425 3700);
DISPLAY INVISIBLE (-1425 3700);
FORCEPROP 2 LAST CDS_LIB pure_quanta
J 0
(-1475 3525);
PAINT MONO (-1475 3525);
DISPLAY INVISIBLE (-1475 3525);
FORCEPROP 2 LAST CDS_LOCATION R1289
J 0
(-1425 3750);
DISPLAY 1.021277 (-1425 3750);
DISPLAY INVISIBLE (-1425 3750);
FORCEPROP 2 LAST $SEC 1
J 0
(-1425 3750);
DISPLAY 0.680851 (-1425 3750);
PAINT MONO (-1425 3750);
DISPLAY INVISIBLE (-1425 3750);
FORCEPROP 2 LAST CDS_SEC 1
J 0
(-1425 3750);
DISPLAY 1.021277 (-1425 3750);
DISPLAY INVISIBLE (-1425 3750);
FORCEADD Q_CAP..1
R 2
(-3475 4150);
FORCEPROP 1 LAST PART_NUMBER CH4104K1B00
J 2
(-3525 4000);
DISPLAY 0.510638 (-3525 4000);
DISPLAY INVISIBLE (-3525 4000);
FORCEPROP 1 LAST PACK_TYPE 0402
J 2
(-3525 3950);
DISPLAY 0.510638 (-3525 3950);
FORCEPROP 1 LAST TOLERANCE 10%
J 2
(-3525 4100);
DISPLAY 0.510638 (-3525 4100);
FORCEPROP 1 LAST VOLTAGE 25V
J 2
(-3525 4150);
DISPLAY 0.510638 (-3525 4150);
FORCEPROP 1 LAST VALUE 0.1UF
J 2
(-3525 4200);
DISPLAY 0.510638 (-3525 4200);
FORCEPROP 1 LAST MATERIAL X7R
J 2
(-3525 4050);
DISPLAY 0.510638 (-3525 4050);
FORCEPROP 1 LAST $LOCATION C639
J 2
(-3525 4250);
DISPLAY 0.978723 (-3525 4250);
FORCEPROP 1 LASTPIN (-3475 4250) $PN 1
J 2
(-3485 4230);
DISPLAY 0.787234 (-3485 4230);
FORCEPROP 1 LASTPIN (-3475 4050) $PN 2
J 2
(-3485 4030);
DISPLAY 0.787234 (-3485 4030);
FORCEPROP 1 LAST PATH I22
J 2
(-3525 4300);
DISPLAY 0.978723 (-3525 4300);
PAINT WHITE (-3525 4300);
DISPLAY INVISIBLE (-3525 4300);
FORCEPROP 2 LAST CDS_LIB pure_quanta
J 0
(-3475 4150);
PAINT MONO (-3475 4150);
DISPLAY INVISIBLE (-3475 4150);
FORCEPROP 2 LAST CDS_LOCATION C639
J 0
(-3525 4350);
DISPLAY 1.021277 (-3525 4350);
DISPLAY INVISIBLE (-3525 4350);
FORCEPROP 2 LAST $SEC 1
J 0
(-3525 4350);
DISPLAY 0.680851 (-3525 4350);
PAINT MONO (-3525 4350);
DISPLAY INVISIBLE (-3525 4350);
FORCEPROP 2 LAST CDS_SEC 1
J 0
(-3525 4350);
DISPLAY 1.021277 (-3525 4350);
DISPLAY INVISIBLE (-3525 4350);
FORCEADD UNIVERSAL_GND..1
(-3475 3925);
FORCEPROP 3 LASTPIN (-3475 3975) SIG_NAME GND\g
J 0
(-3465 3985);
DISPLAY 0.659574 (-3465 3985);
PAINT MONO (-3465 3985);
DISPLAY INVISIBLE (-3465 3985);
FORCEPROP 1 LAST PATH I23
J 0
(-3400 3925);
DISPLAY 0.872340 (-3400 3925);
PAINT AQUA (-3400 3925);
DISPLAY INVISIBLE (-3400 3925);
FORCEPROP 2 LAST CDS_LIB logical_power
J 0
(-3475 3925);
PAINT MONO (-3475 3925);
DISPLAY INVISIBLE (-3475 3925);
FORCEPROP 1 LAST HDL_POWER GND
J 1
(-3450 3850);
DISPLAY 0.872340 (-3450 3850);
PAINT GREEN (-3450 3850);
DISPLAY INVISIBLE (-3450 3850);
FORCEADD UNIVERSAL_POWER..1
(-3475 4375);
FORCEPROP 3 LASTPIN (-3475 4325) SIG_NAME P3V3_AUX\g
J 0
(-3465 4335);
DISPLAY 0.659574 (-3465 4335);
PAINT MONO (-3465 4335);
DISPLAY INVISIBLE (-3465 4335);
FORCEPROP 1 LAST HDL_POWER P3V3_AUX
J 1
(-3475 4425);
DISPLAY 0.872340 (-3475 4425);
PAINT GREEN (-3475 4425);
FORCEPROP 1 LAST PATH I24
J 0
(-3425 4400);
DISPLAY 0.872340 (-3425 4400);
PAINT AQUA (-3425 4400);
DISPLAY INVISIBLE (-3425 4400);
FORCEPROP 2 LAST CDS_LIB logical_power
J 0
(-3475 4375);
PAINT MONO (-3475 4375);
DISPLAY INVISIBLE (-3475 4375);
FORCEADD OFFPAGE..5
(-3025 4750);
FORCEPROP 2 LAST $XR0 153 
J 0
(-3280 4750);
DISPLAY 0.638298 (-3280 4750);
PAINT MONO (-3280 4750);
FORCEPROP 2 LAST PATH I25
J 0
(-3275 4800);
DISPLAY 1.021277 (-3275 4800);
DISPLAY INVISIBLE (-3275 4800);
FORCEPROP 2 LAST CDS_LIB standard
J 0
(-3025 4750);
PAINT MONO (-3025 4750);
DISPLAY INVISIBLE (-3025 4750);
FORCEPROP 1 LAST OFFPAGE TRUE
J 0
(-2700 4625);
DISPLAY 0.872340 (-2700 4625);
PAINT GREEN (-2700 4625);
DISPLAY INVISIBLE (-2700 4625);
FORCEPROP 1 LAST COMMENT_BODY TRUE
J 0
(-2925 4675);
DISPLAY 0.872340 (-2925 4675);
PAINT GREEN (-2925 4675);
DISPLAY INVISIBLE (-2925 4675);
FORCEADD OFFPAGE..5
(-3025 4900);
FORCEPROP 2 LAST $XR0 153 
J 0
(-3280 4900);
DISPLAY 0.638298 (-3280 4900);
PAINT MONO (-3280 4900);
FORCEPROP 2 LAST PATH I26
J 0
(-3275 4950);
DISPLAY 1.021277 (-3275 4950);
DISPLAY INVISIBLE (-3275 4950);
FORCEPROP 1 LAST COMMENT_BODY TRUE
J 0
(-2925 4825);
DISPLAY 0.872340 (-2925 4825);
PAINT GREEN (-2925 4825);
DISPLAY INVISIBLE (-2925 4825);
FORCEPROP 1 LAST OFFPAGE TRUE
J 0
(-2700 4775);
DISPLAY 0.872340 (-2700 4775);
PAINT GREEN (-2700 4775);
DISPLAY INVISIBLE (-2700 4775);
FORCEPROP 2 LAST CDS_LIB standard
J 0
(-3025 4900);
PAINT MONO (-3025 4900);
DISPLAY INVISIBLE (-3025 4900);
FORCEADD OFFPAGE..5
(-3025 5050);
FORCEPROP 2 LAST $XR0 153 
J 0
(-3280 5050);
DISPLAY 0.638298 (-3280 5050);
PAINT MONO (-3280 5050);
FORCEPROP 2 LAST PATH I27
J 0
(-3275 5100);
DISPLAY 1.021277 (-3275 5100);
DISPLAY INVISIBLE (-3275 5100);
FORCEPROP 1 LAST COMMENT_BODY TRUE
J 0
(-2925 4975);
DISPLAY 0.872340 (-2925 4975);
PAINT GREEN (-2925 4975);
DISPLAY INVISIBLE (-2925 4975);
FORCEPROP 1 LAST OFFPAGE TRUE
J 0
(-2700 4925);
DISPLAY 0.872340 (-2700 4925);
PAINT GREEN (-2700 4925);
DISPLAY INVISIBLE (-2700 4925);
FORCEPROP 2 LAST CDS_LIB standard
J 0
(-3025 5050);
PAINT MONO (-3025 5050);
DISPLAY INVISIBLE (-3025 5050);
FORCEADD OFFPAGE..5
(-3025 5200);
FORCEPROP 2 LAST $XR0 153 
J 0
(-3280 5200);
DISPLAY 0.638298 (-3280 5200);
PAINT MONO (-3280 5200);
FORCEPROP 2 LAST PATH I28
J 0
(-3275 5250);
DISPLAY 1.021277 (-3275 5250);
DISPLAY INVISIBLE (-3275 5250);
FORCEPROP 1 LAST COMMENT_BODY TRUE
J 0
(-2925 5125);
DISPLAY 0.872340 (-2925 5125);
PAINT GREEN (-2925 5125);
DISPLAY INVISIBLE (-2925 5125);
FORCEPROP 1 LAST OFFPAGE TRUE
J 0
(-2700 5075);
DISPLAY 0.872340 (-2700 5075);
PAINT GREEN (-2700 5075);
DISPLAY INVISIBLE (-2700 5075);
FORCEPROP 2 LAST CDS_LIB standard
J 0
(-3025 5200);
PAINT MONO (-3025 5200);
DISPLAY INVISIBLE (-3025 5200);
FORCEADD UNIVERSAL_GND..1
(-2175 4575);
FORCEPROP 3 LASTPIN (-2175 4625) SIG_NAME GND\g
J 0
(-2165 4635);
DISPLAY 0.659574 (-2165 4635);
PAINT MONO (-2165 4635);
DISPLAY INVISIBLE (-2165 4635);
FORCEPROP 1 LAST PATH I29
J 0
(-2100 4575);
DISPLAY 0.872340 (-2100 4575);
PAINT AQUA (-2100 4575);
DISPLAY INVISIBLE (-2100 4575);
FORCEPROP 2 LAST CDS_LIB logical_power
J 0
(-2175 4575);
PAINT MONO (-2175 4575);
DISPLAY INVISIBLE (-2175 4575);
FORCEPROP 1 LAST HDL_POWER GND
J 1
(-2150 4500);
DISPLAY 0.872340 (-2150 4500);
PAINT GREEN (-2150 4500);
DISPLAY INVISIBLE (-2150 4500);
FORCEADD Q_RES..1
(-4750 1950);
FORCEPROP 1 LAST PART_NUMBER CS03322FB03
J 0
(-4850 1775);
DISPLAY 0.510638 (-4850 1775);
DISPLAY INVISIBLE (-4850 1775);
FORCEPROP 1 LAST WATTAGE 1/16W
J 2
(-4575 1825);
DISPLAY 0.510638 (-4575 1825);
FORCEPROP 1 LAST MATERIAL CHIP
J 0
(-4850 1825);
DISPLAY 0.510638 (-4850 1825);
FORCEPROP 1 LAST PACK_TYPE 0402LF
J 0
(-4850 1875);
DISPLAY 0.510638 (-4850 1875);
FORCEPROP 1 LAST VALUE 33.2
J 2
(-4550 1950);
DISPLAY 0.510638 (-4550 1950);
FORCEPROP 1 LAST TOLERANCE 1%
J 0
(-4525 1950);
DISPLAY 0.510638 (-4525 1950);
FORCEPROP 1 LAST $LOCATION R3231
J 0
(-5000 1950);
DISPLAY 0.638298 (-5000 1950);
FORCEPROP 1 LASTPIN (-4850 1950) $PN 1
J 0
(-4838 1962);
DISPLAY 0.787234 (-4838 1962);
FORCEPROP 1 LASTPIN (-4650 1950) $PN 2
J 0
(-4688 1962);
DISPLAY 0.787234 (-4688 1962);
FORCEPROP 1 LAST PATH I3
J 0
(-4800 2100);
DISPLAY 0.978723 (-4800 2100);
PAINT WHITE (-4800 2100);
DISPLAY INVISIBLE (-4800 2100);
FORCEPROP 2 LAST CDS_LIB pure_quanta
J 0
(-4750 1950);
PAINT MONO (-4750 1950);
DISPLAY INVISIBLE (-4750 1950);
FORCEPROP 2 LAST CDS_LOCATION R3231
J 0
(-4800 2150);
DISPLAY 1.021277 (-4800 2150);
DISPLAY INVISIBLE (-4800 2150);
FORCEPROP 2 LAST $SEC 1
J 0
(-4800 2150);
DISPLAY 0.680851 (-4800 2150);
PAINT MONO (-4800 2150);
DISPLAY INVISIBLE (-4800 2150);
FORCEPROP 2 LAST CDS_SEC 1
J 0
(-4800 2150);
DISPLAY 1.021277 (-4800 2150);
DISPLAY INVISIBLE (-4800 2150);
FORCEADD 74CBTLV3126PW..1
R 2
(-1625 5000);
FORCEPROP 1 LAST PART_NUMBER AL003126K08
J 2
(-1377 5408);
DISPLAY 0.723404 (-1377 5408);
PAINT GREEN (-1377 5408);
DISPLAY INVISIBLE (-1377 5408);
FORCEPROP 2 LAST VALUE 74CBTLV3126PW
J 2
(-1400 5500);
DISPLAY 1.021277 (-1400 5500);
FORCEPROP 1 LAST MATERIAL IC
J 2
(-1377 5353);
DISPLAY 0.723404 (-1377 5353);
PAINT GREEN (-1377 5353);
FORCEPROP 2 LAST PART_TYPE SMLF
J 2
(-1400 5550);
DISPLAY 1.021277 (-1400 5550);
FORCEPROP 1 LAST $LOCATION U68
J 2
(-1377 5458);
DISPLAY 0.723404 (-1377 5458);
PAINT GREEN (-1377 5458);
FORCEPROP 2 LASTPIN (-1225 4750) $PN 2
J 0
(-1215 4760);
DISPLAY 0.808511 (-1215 4760);
FORCEPROP 2 LASTPIN (-2025 4750) $PN 3
J 2
(-2035 4760);
DISPLAY 0.808511 (-2035 4760);
FORCEPROP 2 LASTPIN (-1225 4700) $PN 1
J 0
(-1215 4710);
DISPLAY 0.808511 (-1215 4710);
FORCEPROP 2 LASTPIN (-1225 4900) $PN 5
J 0
(-1215 4910);
DISPLAY 0.808511 (-1215 4910);
FORCEPROP 2 LASTPIN (-2025 4900) $PN 6
J 2
(-2035 4910);
DISPLAY 0.808511 (-2035 4910);
FORCEPROP 2 LASTPIN (-1225 4850) $PN 4
J 0
(-1215 4860);
DISPLAY 0.808511 (-1215 4860);
FORCEPROP 2 LASTPIN (-1225 5050) $PN 9
J 0
(-1215 5060);
DISPLAY 0.808511 (-1215 5060);
FORCEPROP 2 LASTPIN (-2025 5050) $PN 8
J 2
(-2035 5060);
DISPLAY 0.808511 (-2035 5060);
FORCEPROP 2 LASTPIN (-1225 5000) $PN 10
J 0
(-1215 5010);
DISPLAY 0.808511 (-1215 5010);
FORCEPROP 2 LASTPIN (-1225 5200) $PN 12
J 0
(-1215 5210);
DISPLAY 0.808511 (-1215 5210);
FORCEPROP 2 LASTPIN (-2025 5200) $PN 11
J 2
(-2035 5210);
DISPLAY 0.808511 (-2035 5210);
FORCEPROP 2 LASTPIN (-1225 5150) $PN 13
J 0
(-1215 5160);
DISPLAY 0.808511 (-1215 5160);
FORCEPROP 2 LASTPIN (-2025 4700) $PN 7
J 2
(-2035 4710);
DISPLAY 0.808511 (-2035 4710);
FORCEPROP 2 LASTPIN (-2025 5250) $PN 14
J 2
(-2035 5260);
DISPLAY 0.808511 (-2035 5260);
FORCEPROP 1 LAST PATH I30
J 2
(-1875 4650);
DISPLAY 0.723404 (-1875 4650);
PAINT GREEN (-1875 4650);
DISPLAY INVISIBLE (-1875 4650);
FORCEPROP 2 LAST CDS_LIB pure_quanta
J 2
(-1625 5000);
PAINT MONO (-1625 5000);
DISPLAY INVISIBLE (-1625 5000);
FORCEPROP 1 LAST NEEDS_NO_SIZE TRUE
J 2
(-1875 4690);
DISPLAY 0.723404 (-1875 4690);
PAINT GREEN (-1875 4690);
DISPLAY INVISIBLE (-1875 4690);
FORCEPROP 1 LAST CDS_LMAN_SYM_OUTLINE -250,350,250,-350
J 2
(-1625 5000);
DISPLAY 0.468085 (-1625 5000);
PAINT GREEN (-1625 5000);
DISPLAY INVISIBLE (-1625 5000);
FORCEPROP 2 LAST CDS_LOCATION U68
J 0
(-1400 5600);
DISPLAY 1.021277 (-1400 5600);
DISPLAY INVISIBLE (-1400 5600);
FORCEPROP 2 LAST $SEC 1
J 0
(-1400 5600);
DISPLAY 0.680851 (-1400 5600);
PAINT MONO (-1400 5600);
DISPLAY INVISIBLE (-1400 5600);
FORCEPROP 2 LAST CDS_SEC 1
J 0
(-1400 5600);
DISPLAY 1.021277 (-1400 5600);
DISPLAY INVISIBLE (-1400 5600);
FORCEADD UNIVERSAL_GND..1
(-2375 5300);
FORCEPROP 3 LASTPIN (-2375 5350) SIG_NAME GND\g
J 0
(-2365 5360);
DISPLAY 0.659574 (-2365 5360);
PAINT MONO (-2365 5360);
DISPLAY INVISIBLE (-2365 5360);
FORCEPROP 1 LAST PATH I31
J 0
(-2300 5300);
DISPLAY 0.872340 (-2300 5300);
PAINT AQUA (-2300 5300);
DISPLAY INVISIBLE (-2300 5300);
FORCEPROP 1 LAST HDL_POWER GND
J 1
(-2350 5225);
DISPLAY 0.872340 (-2350 5225);
PAINT GREEN (-2350 5225);
DISPLAY INVISIBLE (-2350 5225);
FORCEPROP 2 LAST CDS_LIB logical_power
J 0
(-2375 5300);
PAINT MONO (-2375 5300);
DISPLAY INVISIBLE (-2375 5300);
FORCEADD Q_CAP..1
R 2
(-2375 5525);
FORCEPROP 1 LAST PART_NUMBER CH4104K1B00
J 2
(-2425 5375);
DISPLAY 0.510638 (-2425 5375);
DISPLAY INVISIBLE (-2425 5375);
FORCEPROP 1 LAST TOLERANCE 10%
J 2
(-2425 5475);
DISPLAY 0.510638 (-2425 5475);
FORCEPROP 1 LAST PACK_TYPE 0402
J 2
(-2425 5325);
DISPLAY 0.510638 (-2425 5325);
FORCEPROP 1 LAST MATERIAL X7R
J 2
(-2425 5425);
DISPLAY 0.510638 (-2425 5425);
FORCEPROP 1 LAST VOLTAGE 25V
J 2
(-2425 5525);
DISPLAY 0.510638 (-2425 5525);
FORCEPROP 1 LAST VALUE 0.1UF
J 2
(-2425 5575);
DISPLAY 0.510638 (-2425 5575);
FORCEPROP 1 LAST $LOCATION C641
J 2
(-2425 5625);
DISPLAY 0.978723 (-2425 5625);
FORCEPROP 1 LASTPIN (-2375 5625) $PN 1
J 2
(-2385 5605);
DISPLAY 0.787234 (-2385 5605);
FORCEPROP 1 LASTPIN (-2375 5425) $PN 2
J 2
(-2385 5405);
DISPLAY 0.787234 (-2385 5405);
FORCEPROP 1 LAST PATH I32
J 2
(-2425 5675);
DISPLAY 0.978723 (-2425 5675);
PAINT WHITE (-2425 5675);
DISPLAY INVISIBLE (-2425 5675);
FORCEPROP 2 LAST CDS_LIB pure_quanta
J 0
(-2375 5525);
PAINT MONO (-2375 5525);
DISPLAY INVISIBLE (-2375 5525);
FORCEPROP 2 LAST CDS_LOCATION C641
J 0
(-2425 5725);
DISPLAY 1.021277 (-2425 5725);
DISPLAY INVISIBLE (-2425 5725);
FORCEPROP 2 LAST $SEC 1
J 0
(-2425 5725);
DISPLAY 0.680851 (-2425 5725);
PAINT MONO (-2425 5725);
DISPLAY INVISIBLE (-2425 5725);
FORCEPROP 2 LAST CDS_SEC 1
J 0
(-2425 5725);
DISPLAY 1.021277 (-2425 5725);
DISPLAY INVISIBLE (-2425 5725);
FORCEADD UNIVERSAL_POWER..1
(-2175 5850);
FORCEPROP 3 LASTPIN (-2175 5800) SIG_NAME P3V3_AUX\g
J 0
(-2165 5810);
DISPLAY 0.659574 (-2165 5810);
PAINT MONO (-2165 5810);
DISPLAY INVISIBLE (-2165 5810);
FORCEPROP 1 LAST HDL_POWER P3V3_AUX
J 1
(-2175 5900);
DISPLAY 0.872340 (-2175 5900);
PAINT GREEN (-2175 5900);
FORCEPROP 1 LAST PATH I33
J 0
(-2125 5875);
DISPLAY 0.872340 (-2125 5875);
PAINT AQUA (-2125 5875);
DISPLAY INVISIBLE (-2125 5875);
FORCEPROP 2 LAST CDS_LIB logical_power
J 0
(-2175 5850);
PAINT MONO (-2175 5850);
DISPLAY INVISIBLE (-2175 5850);
FORCEADD OFFPAGE..1
(-3025 6325);
FORCEPROP 2 LAST $XR0 153 
J 0
(-3307 6325);
DISPLAY 0.638298 (-3307 6325);
PAINT MONO (-3307 6325);
FORCEPROP 2 LAST PATH I34
J 0
(-3300 6375);
DISPLAY 1.021277 (-3300 6375);
DISPLAY INVISIBLE (-3300 6375);
FORCEPROP 2 LAST CDS_LIB standard
J 0
(-3025 6325);
PAINT MONO (-3025 6325);
DISPLAY INVISIBLE (-3025 6325);
FORCEPROP 1 LAST OFFPAGE TRUE
J 0
(-2700 6200);
DISPLAY 0.872340 (-2700 6200);
PAINT GREEN (-2700 6200);
DISPLAY INVISIBLE (-2700 6200);
FORCEPROP 1 LAST COMMENT_BODY TRUE
J 0
(-2900 6225);
DISPLAY 0.872340 (-2900 6225);
PAINT GREEN (-2900 6225);
DISPLAY INVISIBLE (-2900 6225);
FORCEADD OFFPAGE..1
(-3025 6175);
FORCEPROP 2 LAST $XR0 153 
J 0
(-3307 6175);
DISPLAY 0.638298 (-3307 6175);
PAINT MONO (-3307 6175);
FORCEPROP 2 LAST PATH I35
J 0
(-3300 6225);
DISPLAY 1.021277 (-3300 6225);
DISPLAY INVISIBLE (-3300 6225);
FORCEPROP 2 LAST CDS_LIB standard
J 0
(-3025 6175);
PAINT MONO (-3025 6175);
DISPLAY INVISIBLE (-3025 6175);
FORCEPROP 1 LAST OFFPAGE TRUE
J 0
(-2700 6050);
DISPLAY 0.872340 (-2700 6050);
PAINT GREEN (-2700 6050);
DISPLAY INVISIBLE (-2700 6050);
FORCEPROP 1 LAST COMMENT_BODY TRUE
J 0
(-2900 6075);
DISPLAY 0.872340 (-2900 6075);
PAINT GREEN (-2900 6075);
DISPLAY INVISIBLE (-2900 6075);
FORCEADD OFFPAGE..1
(-3025 6475);
FORCEPROP 2 LAST $XR0 153 
J 0
(-3307 6475);
DISPLAY 0.638298 (-3307 6475);
PAINT MONO (-3307 6475);
FORCEPROP 2 LAST PATH I36
J 0
(-3300 6525);
DISPLAY 1.021277 (-3300 6525);
DISPLAY INVISIBLE (-3300 6525);
FORCEPROP 2 LAST CDS_LIB standard
J 0
(-3025 6475);
PAINT MONO (-3025 6475);
DISPLAY INVISIBLE (-3025 6475);
FORCEPROP 1 LAST OFFPAGE TRUE
J 0
(-2700 6350);
DISPLAY 0.872340 (-2700 6350);
PAINT GREEN (-2700 6350);
DISPLAY INVISIBLE (-2700 6350);
FORCEPROP 1 LAST COMMENT_BODY TRUE
J 0
(-2900 6375);
DISPLAY 0.872340 (-2900 6375);
PAINT GREEN (-2900 6375);
DISPLAY INVISIBLE (-2900 6375);
FORCEADD OFFPAGE..1
(-3025 6625);
FORCEPROP 2 LAST $XR0 153 
J 0
(-3307 6625);
DISPLAY 0.638298 (-3307 6625);
PAINT MONO (-3307 6625);
FORCEPROP 2 LAST PATH I37
J 0
(-3300 6675);
DISPLAY 1.021277 (-3300 6675);
DISPLAY INVISIBLE (-3300 6675);
FORCEPROP 1 LAST COMMENT_BODY TRUE
J 0
(-2900 6525);
DISPLAY 0.872340 (-2900 6525);
PAINT GREEN (-2900 6525);
DISPLAY INVISIBLE (-2900 6525);
FORCEPROP 1 LAST OFFPAGE TRUE
J 0
(-2700 6500);
DISPLAY 0.872340 (-2700 6500);
PAINT GREEN (-2700 6500);
DISPLAY INVISIBLE (-2700 6500);
FORCEPROP 2 LAST CDS_LIB standard
J 0
(-3025 6625);
PAINT MONO (-3025 6625);
DISPLAY INVISIBLE (-3025 6625);
FORCEADD UNIVERSAL_GND..1
(-2175 6000);
FORCEPROP 3 LASTPIN (-2175 6050) SIG_NAME GND\g
J 0
(-2165 6060);
DISPLAY 0.659574 (-2165 6060);
PAINT MONO (-2165 6060);
DISPLAY INVISIBLE (-2165 6060);
FORCEPROP 1 LAST PATH I38
J 0
(-2100 6000);
DISPLAY 0.872340 (-2100 6000);
PAINT AQUA (-2100 6000);
DISPLAY INVISIBLE (-2100 6000);
FORCEPROP 1 LAST HDL_POWER GND
J 1
(-2150 5925);
DISPLAY 0.872340 (-2150 5925);
PAINT GREEN (-2150 5925);
DISPLAY INVISIBLE (-2150 5925);
FORCEPROP 2 LAST CDS_LIB logical_power
J 0
(-2175 6000);
PAINT MONO (-2175 6000);
DISPLAY INVISIBLE (-2175 6000);
FORCEADD 74CBTLV3126PW..1
R 2
(-1625 6425);
FORCEPROP 1 LAST PART_NUMBER AL003126K08
J 2
(-1377 6833);
DISPLAY 0.723404 (-1377 6833);
PAINT GREEN (-1377 6833);
DISPLAY INVISIBLE (-1377 6833);
FORCEPROP 2 LAST PART_TYPE SMLF
J 2
(-1400 6975);
DISPLAY 1.021277 (-1400 6975);
FORCEPROP 2 LAST VALUE 74CBTLV3126PW
J 2
(-1400 6925);
DISPLAY 1.021277 (-1400 6925);
FORCEPROP 1 LAST MATERIAL IC
J 2
(-1377 6778);
DISPLAY 0.723404 (-1377 6778);
PAINT GREEN (-1377 6778);
FORCEPROP 1 LAST $LOCATION U67
J 2
(-1377 6883);
DISPLAY 0.723404 (-1377 6883);
PAINT GREEN (-1377 6883);
FORCEPROP 2 LASTPIN (-1225 6175) $PN 2
J 0
(-1215 6185);
DISPLAY 0.808511 (-1215 6185);
FORCEPROP 2 LASTPIN (-2025 6175) $PN 3
J 2
(-2035 6185);
DISPLAY 0.808511 (-2035 6185);
FORCEPROP 2 LASTPIN (-1225 6125) $PN 1
J 0
(-1215 6135);
DISPLAY 0.808511 (-1215 6135);
FORCEPROP 2 LASTPIN (-1225 6325) $PN 5
J 0
(-1215 6335);
DISPLAY 0.808511 (-1215 6335);
FORCEPROP 2 LASTPIN (-2025 6325) $PN 6
J 2
(-2035 6335);
DISPLAY 0.808511 (-2035 6335);
FORCEPROP 2 LASTPIN (-1225 6275) $PN 4
J 0
(-1215 6285);
DISPLAY 0.808511 (-1215 6285);
FORCEPROP 2 LASTPIN (-1225 6475) $PN 9
J 0
(-1215 6485);
DISPLAY 0.808511 (-1215 6485);
FORCEPROP 2 LASTPIN (-2025 6475) $PN 8
J 2
(-2035 6485);
DISPLAY 0.808511 (-2035 6485);
FORCEPROP 2 LASTPIN (-1225 6425) $PN 10
J 0
(-1215 6435);
DISPLAY 0.808511 (-1215 6435);
FORCEPROP 2 LASTPIN (-1225 6625) $PN 12
J 0
(-1215 6635);
DISPLAY 0.808511 (-1215 6635);
FORCEPROP 2 LASTPIN (-2025 6625) $PN 11
J 2
(-2035 6635);
DISPLAY 0.808511 (-2035 6635);
FORCEPROP 2 LASTPIN (-1225 6575) $PN 13
J 0
(-1215 6585);
DISPLAY 0.808511 (-1215 6585);
FORCEPROP 2 LASTPIN (-2025 6125) $PN 7
J 2
(-2035 6135);
DISPLAY 0.808511 (-2035 6135);
FORCEPROP 2 LASTPIN (-2025 6675) $PN 14
J 2
(-2035 6685);
DISPLAY 0.808511 (-2035 6685);
FORCEPROP 1 LAST PATH I39
J 2
(-1875 6075);
DISPLAY 0.723404 (-1875 6075);
PAINT GREEN (-1875 6075);
DISPLAY INVISIBLE (-1875 6075);
FORCEPROP 2 LAST CDS_LIB pure_quanta
J 2
(-1625 6425);
PAINT MONO (-1625 6425);
DISPLAY INVISIBLE (-1625 6425);
FORCEPROP 1 LAST NEEDS_NO_SIZE TRUE
J 2
(-1875 6115);
DISPLAY 0.723404 (-1875 6115);
PAINT GREEN (-1875 6115);
DISPLAY INVISIBLE (-1875 6115);
FORCEPROP 1 LAST CDS_LMAN_SYM_OUTLINE -250,350,250,-350
J 2
(-1625 6425);
DISPLAY 0.468085 (-1625 6425);
PAINT GREEN (-1625 6425);
DISPLAY INVISIBLE (-1625 6425);
FORCEPROP 2 LAST CDS_LOCATION U67
J 0
(-1400 7025);
DISPLAY 1.021277 (-1400 7025);
DISPLAY INVISIBLE (-1400 7025);
FORCEPROP 2 LAST $SEC 1
J 0
(-1400 7025);
DISPLAY 0.680851 (-1400 7025);
PAINT MONO (-1400 7025);
DISPLAY INVISIBLE (-1400 7025);
FORCEPROP 2 LAST CDS_SEC 1
J 0
(-1400 7025);
DISPLAY 1.021277 (-1400 7025);
DISPLAY INVISIBLE (-1400 7025);
FORCEADD OFFPAGE..1
(-4625 2050);
FORCEPROP 2 LAST $XR7 245 
J 0
(-5717 2050);
DISPLAY 0.638298 (-5717 2050);
PAINT MONO (-5717 2050);
FORCEPROP 2 LAST $XR6 236 
J 0
(-5597 2050);
DISPLAY 0.638298 (-5597 2050);
PAINT MONO (-5597 2050);
FORCEPROP 2 LAST $XR5 233 
J 0
(-5477 2050);
DISPLAY 0.638298 (-5477 2050);
PAINT MONO (-5477 2050);
FORCEPROP 2 LAST $XR4 231 
J 0
(-5357 2050);
DISPLAY 0.638298 (-5357 2050);
PAINT MONO (-5357 2050);
FORCEPROP 2 LAST $XR3 227 
J 0
(-5237 2050);
DISPLAY 0.638298 (-5237 2050);
PAINT MONO (-5237 2050);
FORCEPROP 2 LAST $XR2 191 
J 0
(-5117 2050);
DISPLAY 0.638298 (-5117 2050);
PAINT MONO (-5117 2050);
FORCEPROP 2 LAST $XR1 161 
J 0
(-4997 2050);
DISPLAY 0.638298 (-4997 2050);
PAINT MONO (-4997 2050);
FORCEPROP 2 LAST $XR0 215 
J 0
(-4877 2050);
DISPLAY 0.638298 (-4877 2050);
PAINT MONO (-4877 2050);
FORCEPROP 2 LAST PATH I4
J 0
(-4875 2100);
DISPLAY 1.021277 (-4875 2100);
DISPLAY INVISIBLE (-4875 2100);
FORCEPROP 2 LAST CDS_LIB standard
J 0
(-4625 2050);
PAINT MONO (-4625 2050);
DISPLAY INVISIBLE (-4625 2050);
FORCEPROP 1 LAST COMMENT_BODY TRUE
J 0
(-4500 1950);
DISPLAY 0.872340 (-4500 1950);
PAINT GREEN (-4500 1950);
DISPLAY INVISIBLE (-4500 1950);
FORCEPROP 1 LAST OFFPAGE TRUE
J 0
(-4300 1925);
DISPLAY 0.872340 (-4300 1925);
PAINT GREEN (-4300 1925);
DISPLAY INVISIBLE (-4300 1925);
FORCEADD Q_CAP..1
R 2
(-2375 6950);
FORCEPROP 1 LAST PART_NUMBER CH4104K1B00
J 2
(-2425 6800);
DISPLAY 0.510638 (-2425 6800);
DISPLAY INVISIBLE (-2425 6800);
FORCEPROP 1 LAST VOLTAGE 25V
J 2
(-2425 6950);
DISPLAY 0.510638 (-2425 6950);
FORCEPROP 1 LAST VALUE 0.1UF
J 2
(-2425 7000);
DISPLAY 0.510638 (-2425 7000);
FORCEPROP 1 LAST MATERIAL X7R
J 2
(-2425 6850);
DISPLAY 0.510638 (-2425 6850);
FORCEPROP 1 LAST PACK_TYPE 0402
J 2
(-2425 6750);
DISPLAY 0.510638 (-2425 6750);
FORCEPROP 1 LAST TOLERANCE 10%
J 2
(-2425 6900);
DISPLAY 0.510638 (-2425 6900);
FORCEPROP 1 LAST $LOCATION C640
J 2
(-2425 7050);
DISPLAY 0.978723 (-2425 7050);
FORCEPROP 1 LASTPIN (-2375 7050) $PN 1
J 2
(-2385 7030);
DISPLAY 0.787234 (-2385 7030);
FORCEPROP 1 LASTPIN (-2375 6850) $PN 2
J 2
(-2385 6830);
DISPLAY 0.787234 (-2385 6830);
FORCEPROP 1 LAST PATH I40
J 2
(-2425 7100);
DISPLAY 0.978723 (-2425 7100);
PAINT WHITE (-2425 7100);
DISPLAY INVISIBLE (-2425 7100);
FORCEPROP 2 LAST CDS_LIB pure_quanta
J 0
(-2375 6950);
PAINT MONO (-2375 6950);
DISPLAY INVISIBLE (-2375 6950);
FORCEPROP 2 LAST CDS_LOCATION C640
J 0
(-2425 7150);
DISPLAY 1.021277 (-2425 7150);
DISPLAY INVISIBLE (-2425 7150);
FORCEPROP 2 LAST $SEC 1
J 0
(-2425 7150);
DISPLAY 0.680851 (-2425 7150);
PAINT MONO (-2425 7150);
DISPLAY INVISIBLE (-2425 7150);
FORCEPROP 2 LAST CDS_SEC 1
J 0
(-2425 7150);
DISPLAY 1.021277 (-2425 7150);
DISPLAY INVISIBLE (-2425 7150);
FORCEADD UNIVERSAL_GND..1
(-2375 6725);
FORCEPROP 3 LASTPIN (-2375 6775) SIG_NAME GND\g
J 0
(-2365 6785);
DISPLAY 0.659574 (-2365 6785);
PAINT MONO (-2365 6785);
DISPLAY INVISIBLE (-2365 6785);
FORCEPROP 1 LAST PATH I41
J 0
(-2300 6725);
DISPLAY 0.872340 (-2300 6725);
PAINT AQUA (-2300 6725);
DISPLAY INVISIBLE (-2300 6725);
FORCEPROP 2 LAST CDS_LIB logical_power
J 0
(-2375 6725);
PAINT MONO (-2375 6725);
DISPLAY INVISIBLE (-2375 6725);
FORCEPROP 1 LAST HDL_POWER GND
J 1
(-2350 6650);
DISPLAY 0.872340 (-2350 6650);
PAINT GREEN (-2350 6650);
DISPLAY INVISIBLE (-2350 6650);
FORCEADD UNIVERSAL_POWER..1
(-2175 7275);
FORCEPROP 3 LASTPIN (-2175 7225) SIG_NAME P3V3_AUX\g
J 0
(-2165 7235);
DISPLAY 0.659574 (-2165 7235);
PAINT MONO (-2165 7235);
DISPLAY INVISIBLE (-2165 7235);
FORCEPROP 1 LAST HDL_POWER P3V3_AUX
J 1
(-2175 7325);
DISPLAY 0.872340 (-2175 7325);
PAINT GREEN (-2175 7325);
FORCEPROP 1 LAST PATH I42
J 0
(-2125 7300);
DISPLAY 0.872340 (-2125 7300);
PAINT AQUA (-2125 7300);
DISPLAY INVISIBLE (-2125 7300);
FORCEPROP 2 LAST CDS_LIB logical_power
J 0
(-2175 7275);
PAINT MONO (-2175 7275);
DISPLAY INVISIBLE (-2175 7275);
FORCEADD Q_RES..2
(475 1825);
FORCEPROP 1 LAST PART_NUMBER CS11002FB07
J 0
(515 1700);
DISPLAY 0.638298 (515 1700);
DISPLAY INVISIBLE (515 1700);
FORCEPROP 1 LAST PACK_TYPE 0402LF
J 0
(525 1700);
DISPLAY 0.638298 (525 1700);
FORCEPROP 1 LAST WATTAGE 1/16W
J 0
(515 1800);
DISPLAY 0.638298 (515 1800);
FORCEPROP 1 LAST MATERIAL CHIP
J 0
(515 1750);
DISPLAY 0.638298 (515 1750);
FORCEPROP 1 LAST TOLERANCE 1%
J 0
(520 1850);
DISPLAY 0.638298 (520 1850);
FORCEPROP 1 LAST VALUE 100
J 0
(520 1900);
DISPLAY 0.638298 (520 1900);
FORCEPROP 1 LAST $LOCATION R1896
J 0
(520 1950);
DISPLAY 0.638298 (520 1950);
FORCEPROP 1 LASTPIN (475 1925) $PN 1
J 0
(480 1887);
DISPLAY 0.787234 (480 1887);
PAINT MONO (480 1887);
FORCEPROP 1 LASTPIN (475 1725) $PN 2
J 0
(480 1735);
DISPLAY 0.787234 (480 1735);
PAINT MONO (480 1735);
FORCEPROP 1 LAST PATH I43
J 0
(525 2000);
DISPLAY 0.978723 (525 2000);
PAINT WHITE (525 2000);
DISPLAY INVISIBLE (525 2000);
FORCEPROP 2 LAST CDS_LIB pure_quanta
J 0
(475 1825);
DISPLAY INVISIBLE (475 1825);
FORCEPROP 0 LAST CDS_LOCATION R1896
J 0
(525 2000);
DISPLAY 1.021277 (525 2000);
DISPLAY INVISIBLE (525 2000);
FORCEPROP 0 LAST $SEC 1
J 0
(525 2000);
DISPLAY 0.680851 (525 2000);
PAINT MONO (525 2000);
DISPLAY INVISIBLE (525 2000);
FORCEPROP 0 LAST CDS_SEC 1
J 0
(525 2000);
DISPLAY 1.021277 (525 2000);
DISPLAY INVISIBLE (525 2000);
FORCEADD OFFPAGE..2
(-1300 2000);
FORCEPROP 2 LAST $XR0 153 
J 0
(-1111 2000);
DISPLAY 0.638298 (-1111 2000);
PAINT MONO (-1111 2000);
FORCEPROP 2 LAST PATH I44
J 0
(-1100 2050);
DISPLAY 1.021277 (-1100 2050);
DISPLAY INVISIBLE (-1100 2050);
FORCEPROP 1 LAST COMMENT_BODY TRUE
J 0
(-1345 1905);
DISPLAY 0.872340 (-1345 1905);
PAINT GREEN (-1345 1905);
DISPLAY INVISIBLE (-1345 1905);
FORCEPROP 1 LAST OFFPAGE TRUE
J 0
(-975 1875);
DISPLAY 0.872340 (-975 1875);
PAINT GREEN (-975 1875);
DISPLAY INVISIBLE (-975 1875);
FORCEPROP 2 LAST CDS_LIB standard
J 0
(-1300 2000);
DISPLAY INVISIBLE (-1300 2000);
FORCEADD OFFPAGE..5
R 2
(-800 3725);
FORCEPROP 2 LAST $XR0 155 
J 0
(-611 3725);
DISPLAY 0.638298 (-611 3725);
PAINT MONO (-611 3725);
FORCEPROP 2 LAST PATH I45
J 0
(-600 3775);
DISPLAY 1.021277 (-600 3775);
DISPLAY INVISIBLE (-600 3775);
FORCEPROP 2 LAST CDS_LIB standard
J 2
(-800 3725);
DISPLAY INVISIBLE (-800 3725);
FORCEPROP 1 LAST COMMENT_BODY TRUE
J 2
(-900 3650);
DISPLAY 0.872340 (-900 3650);
PAINT GREEN (-900 3650);
DISPLAY INVISIBLE (-900 3650);
FORCEPROP 1 LAST OFFPAGE TRUE
J 2
(-1125 3600);
DISPLAY 0.872340 (-1125 3600);
PAINT GREEN (-1125 3600);
DISPLAY INVISIBLE (-1125 3600);
FORCEADD OFFPAGE..5
(300 3275);
FORCEPROP 2 LAST $XR0 240 
J 0
(45 3275);
DISPLAY 0.638298 (45 3275);
PAINT MONO (45 3275);
FORCEPROP 2 LAST PATH I46
J 0
(50 3325);
DISPLAY 1.021277 (50 3325);
DISPLAY INVISIBLE (50 3325);
FORCEPROP 1 LAST OFFPAGE TRUE
J 0
(625 3150);
DISPLAY 0.872340 (625 3150);
PAINT GREEN (625 3150);
DISPLAY INVISIBLE (625 3150);
FORCEPROP 1 LAST COMMENT_BODY TRUE
J 0
(400 3200);
DISPLAY 0.872340 (400 3200);
PAINT GREEN (400 3200);
DISPLAY INVISIBLE (400 3200);
FORCEPROP 2 LAST CDS_LIB standard
J 0
(300 3275);
PAINT MONO (300 3275);
DISPLAY INVISIBLE (300 3275);
FORCEADD OFFPAGE..5
(300 3450);
FORCEPROP 2 LAST $XR2 160 
J 0
(-195 3450);
DISPLAY 0.638298 (-195 3450);
PAINT MONO (-195 3450);
FORCEPROP 2 LAST $XR1 154 
J 0
(-75 3450);
DISPLAY 0.638298 (-75 3450);
PAINT MONO (-75 3450);
FORCEPROP 2 LAST $XR0 240 
J 0
(45 3450);
DISPLAY 0.638298 (45 3450);
PAINT MONO (45 3450);
FORCEPROP 2 LAST PATH I47
J 0
(50 3500);
DISPLAY 1.021277 (50 3500);
DISPLAY INVISIBLE (50 3500);
FORCEPROP 2 LAST CDS_LIB standard
J 0
(300 3450);
PAINT MONO (300 3450);
DISPLAY INVISIBLE (300 3450);
FORCEPROP 1 LAST COMMENT_BODY TRUE
J 0
(400 3375);
DISPLAY 0.872340 (400 3375);
PAINT GREEN (400 3375);
DISPLAY INVISIBLE (400 3375);
FORCEPROP 1 LAST OFFPAGE TRUE
J 0
(625 3325);
DISPLAY 0.872340 (625 3325);
PAINT GREEN (625 3325);
DISPLAY INVISIBLE (625 3325);
FORCEADD OFFPAGE..5
(300 3600);
FORCEPROP 2 LAST $XR2 160 
J 0
(-195 3600);
DISPLAY 0.638298 (-195 3600);
PAINT MONO (-195 3600);
FORCEPROP 2 LAST $XR1 154 
J 0
(-75 3600);
DISPLAY 0.638298 (-75 3600);
PAINT MONO (-75 3600);
FORCEPROP 2 LAST $XR0 240 
J 0
(45 3600);
DISPLAY 0.638298 (45 3600);
PAINT MONO (45 3600);
FORCEPROP 2 LAST PATH I48
J 0
(50 3650);
DISPLAY 1.021277 (50 3650);
DISPLAY INVISIBLE (50 3650);
FORCEPROP 2 LAST CDS_LIB standard
J 0
(300 3600);
PAINT MONO (300 3600);
DISPLAY INVISIBLE (300 3600);
FORCEPROP 1 LAST COMMENT_BODY TRUE
J 0
(400 3525);
DISPLAY 0.872340 (400 3525);
PAINT GREEN (400 3525);
DISPLAY INVISIBLE (400 3525);
FORCEPROP 1 LAST OFFPAGE TRUE
J 0
(625 3475);
DISPLAY 0.872340 (625 3475);
PAINT GREEN (625 3475);
DISPLAY INVISIBLE (625 3475);
FORCEADD OFFPAGE..5
(300 3750);
FORCEPROP 2 LAST $XR2 160 
J 0
(-195 3750);
DISPLAY 0.638298 (-195 3750);
PAINT MONO (-195 3750);
FORCEPROP 2 LAST $XR1 154 
J 0
(-75 3750);
DISPLAY 0.638298 (-75 3750);
PAINT MONO (-75 3750);
FORCEPROP 2 LAST $XR0 240 
J 0
(45 3750);
DISPLAY 0.638298 (45 3750);
PAINT MONO (45 3750);
FORCEPROP 2 LAST PATH I49
J 0
(50 3800);
DISPLAY 1.021277 (50 3800);
DISPLAY INVISIBLE (50 3800);
FORCEPROP 1 LAST OFFPAGE TRUE
J 0
(625 3625);
DISPLAY 0.872340 (625 3625);
PAINT GREEN (625 3625);
DISPLAY INVISIBLE (625 3625);
FORCEPROP 1 LAST COMMENT_BODY TRUE
J 0
(400 3675);
DISPLAY 0.872340 (400 3675);
PAINT GREEN (400 3675);
DISPLAY INVISIBLE (400 3675);
FORCEPROP 2 LAST CDS_LIB standard
J 0
(300 3750);
PAINT MONO (300 3750);
DISPLAY INVISIBLE (300 3750);
FORCEADD Q_RES..1
(-4675 3675);
FORCEPROP 1 LAST PART_NUMBER CS03322FB03
J 0
(-4800 3475);
DISPLAY 0.510638 (-4800 3475);
DISPLAY INVISIBLE (-4800 3475);
FORCEPROP 1 LAST PACK_TYPE 0402LF
J 0
(-4800 3575);
DISPLAY 0.510638 (-4800 3575);
FORCEPROP 1 LAST WATTAGE 1/16W
J 2
(-4525 3525);
DISPLAY 0.510638 (-4525 3525);
FORCEPROP 1 LAST VALUE 33.2
J 2
(-4475 3675);
DISPLAY 0.510638 (-4475 3675);
FORCEPROP 1 LAST TOLERANCE 1%
J 0
(-4450 3675);
DISPLAY 0.510638 (-4450 3675);
FORCEPROP 1 LAST MATERIAL CHIP
J 0
(-4800 3525);
DISPLAY 0.510638 (-4800 3525);
FORCEPROP 1 LAST $LOCATION R1719
J 0
(-4925 3675);
DISPLAY 0.638298 (-4925 3675);
FORCEPROP 1 LASTPIN (-4775 3675) $PN 1
J 0
(-4763 3687);
DISPLAY 0.787234 (-4763 3687);
FORCEPROP 1 LASTPIN (-4575 3675) $PN 2
J 0
(-4613 3687);
DISPLAY 0.787234 (-4613 3687);
FORCEPROP 1 LAST PATH I5
J 0
(-4725 3825);
DISPLAY 0.978723 (-4725 3825);
PAINT WHITE (-4725 3825);
DISPLAY INVISIBLE (-4725 3825);
FORCEPROP 2 LAST CDS_LIB pure_quanta
J 0
(-4675 3675);
PAINT MONO (-4675 3675);
DISPLAY INVISIBLE (-4675 3675);
FORCEPROP 2 LAST CDS_LOCATION R1719
J 0
(-4725 3875);
DISPLAY 1.021277 (-4725 3875);
DISPLAY INVISIBLE (-4725 3875);
FORCEPROP 2 LAST $SEC 1
J 0
(-4725 3875);
DISPLAY 0.680851 (-4725 3875);
PAINT MONO (-4725 3875);
DISPLAY INVISIBLE (-4725 3875);
FORCEPROP 2 LAST CDS_SEC 1
J 0
(-4725 3875);
DISPLAY 1.021277 (-4725 3875);
DISPLAY INVISIBLE (-4725 3875);
FORCEADD Q_RES..2
(725 1825);
FORCEPROP 1 LAST PART_NUMBER CS11002FB07
J 0
(765 1700);
DISPLAY 0.638298 (765 1700);
DISPLAY INVISIBLE (765 1700);
FORCEPROP 1 LAST WATTAGE 1/16W
J 0
(765 1800);
DISPLAY 0.638298 (765 1800);
FORCEPROP 1 LAST TOLERANCE 1%
J 0
(770 1850);
DISPLAY 0.638298 (770 1850);
FORCEPROP 1 LAST VALUE 100
J 0
(770 1900);
DISPLAY 0.638298 (770 1900);
FORCEPROP 1 LAST MATERIAL CHIP
J 0
(765 1750);
DISPLAY 0.638298 (765 1750);
FORCEPROP 1 LAST PACK_TYPE 0402LF
J 0
(775 1700);
DISPLAY 0.638298 (775 1700);
FORCEPROP 1 LAST $LOCATION R1897
J 0
(770 1950);
DISPLAY 0.638298 (770 1950);
FORCEPROP 1 LASTPIN (725 1925) $PN 1
J 0
(730 1887);
DISPLAY 0.787234 (730 1887);
PAINT MONO (730 1887);
FORCEPROP 1 LASTPIN (725 1725) $PN 2
J 0
(730 1735);
DISPLAY 0.787234 (730 1735);
PAINT MONO (730 1735);
FORCEPROP 1 LAST PATH I50
J 0
(775 2000);
DISPLAY 0.978723 (775 2000);
PAINT WHITE (775 2000);
DISPLAY INVISIBLE (775 2000);
FORCEPROP 2 LAST CDS_LIB pure_quanta
J 0
(725 1825);
DISPLAY INVISIBLE (725 1825);
FORCEPROP 0 LAST CDS_LOCATION R1897
J 0
(775 2000);
DISPLAY 1.021277 (775 2000);
DISPLAY INVISIBLE (775 2000);
FORCEPROP 0 LAST $SEC 1
J 0
(775 2000);
DISPLAY 0.680851 (775 2000);
PAINT MONO (775 2000);
DISPLAY INVISIBLE (775 2000);
FORCEPROP 0 LAST CDS_SEC 1
J 0
(775 2000);
DISPLAY 1.021277 (775 2000);
DISPLAY INVISIBLE (775 2000);
FORCEADD UNIVERSAL_GND..1
(975 1550);
FORCEPROP 3 LASTPIN (975 1600) SIG_NAME GND\g
J 0
(985 1610);
DISPLAY 0.659574 (985 1610);
PAINT MONO (985 1610);
DISPLAY INVISIBLE (985 1610);
FORCEPROP 1 LAST PATH I51
J 0
(1050 1550);
DISPLAY 0.872340 (1050 1550);
PAINT AQUA (1050 1550);
DISPLAY INVISIBLE (1050 1550);
FORCEPROP 1 LAST HDL_POWER GND
J 1
(1000 1475);
DISPLAY 0.872340 (1000 1475);
PAINT GREEN (1000 1475);
DISPLAY INVISIBLE (1000 1475);
FORCEPROP 2 LAST CDS_LIB logical_power
J 0
(975 1550);
DISPLAY INVISIBLE (975 1550);
FORCEADD Q_RES..2
(975 1825);
FORCEPROP 1 LAST PART_NUMBER CS11002FB07
J 0
(1015 1700);
DISPLAY 0.638298 (1015 1700);
DISPLAY INVISIBLE (1015 1700);
FORCEPROP 1 LAST PACK_TYPE 0402LF
J 0
(1015 1650);
DISPLAY 0.638298 (1015 1650);
FORCEPROP 1 LAST MATERIAL CHIP
J 0
(1015 1750);
DISPLAY 0.638298 (1015 1750);
FORCEPROP 1 LAST WATTAGE 1/16W
J 0
(1015 1800);
DISPLAY 0.638298 (1015 1800);
FORCEPROP 1 LAST VALUE 100
J 0
(1020 1900);
DISPLAY 0.638298 (1020 1900);
FORCEPROP 1 LAST TOLERANCE 1%
J 0
(1020 1850);
DISPLAY 0.638298 (1020 1850);
FORCEPROP 1 LAST $LOCATION R1898
J 0
(1020 1950);
DISPLAY 0.638298 (1020 1950);
FORCEPROP 1 LASTPIN (975 1925) $PN 1
J 0
(980 1887);
DISPLAY 0.787234 (980 1887);
PAINT MONO (980 1887);
FORCEPROP 1 LASTPIN (975 1725) $PN 2
J 0
(980 1735);
DISPLAY 0.787234 (980 1735);
PAINT MONO (980 1735);
FORCEPROP 1 LAST PATH I52
J 0
(1025 2000);
DISPLAY 0.978723 (1025 2000);
PAINT WHITE (1025 2000);
DISPLAY INVISIBLE (1025 2000);
FORCEPROP 2 LAST CDS_LIB pure_quanta
J 0
(975 1825);
DISPLAY INVISIBLE (975 1825);
FORCEPROP 0 LAST CDS_LOCATION R1898
J 0
(1025 2000);
DISPLAY 1.021277 (1025 2000);
DISPLAY INVISIBLE (1025 2000);
FORCEPROP 0 LAST $SEC 1
J 0
(1025 2000);
DISPLAY 0.680851 (1025 2000);
PAINT MONO (1025 2000);
DISPLAY INVISIBLE (1025 2000);
FORCEPROP 0 LAST CDS_SEC 1
J 0
(1025 2000);
DISPLAY 1.021277 (1025 2000);
DISPLAY INVISIBLE (1025 2000);
FORCEADD Q_RES..1
(1625 3275);
FORCEPROP 1 LAST PART_NUMBER CS21002FB06
J 0
(1475 3325);
DISPLAY 0.510638 (1475 3325);
DISPLAY INVISIBLE (1475 3325);
FORCEPROP 1 LAST PACK_TYPE 0402LF
J 0
(1475 3375);
DISPLAY 0.510638 (1475 3375);
FORCEPROP 1 LAST TOLERANCE 1%
J 0
(1875 3275);
DISPLAY 0.638298 (1875 3275);
FORCEPROP 1 LAST WATTAGE 1/16W
J 2
(1825 3375);
DISPLAY 0.638298 (1825 3375);
FORCEPROP 1 LAST VALUE 1K
J 2
(1825 3275);
DISPLAY 0.638298 (1825 3275);
FORCEPROP 1 LAST MATERIAL CHIP
J 0
(1975 3275);
DISPLAY 0.638298 (1975 3275);
FORCEPROP 1 LAST $LOCATION R1356
J 0
(1400 3275);
DISPLAY 0.510638 (1400 3275);
FORCEPROP 1 LASTPIN (1525 3275) $PN 1
J 0
(1537 3287);
DISPLAY 0.787234 (1537 3287);
FORCEPROP 1 LASTPIN (1725 3275) $PN 2
J 0
(1687 3287);
DISPLAY 0.787234 (1687 3287);
FORCEPROP 1 LAST PATH I53
J 0
(1575 3425);
DISPLAY 0.978723 (1575 3425);
PAINT WHITE (1575 3425);
DISPLAY INVISIBLE (1575 3425);
FORCEPROP 2 LAST CDS_LIB pure_quanta
J 0
(1625 3275);
PAINT MONO (1625 3275);
DISPLAY INVISIBLE (1625 3275);
FORCEPROP 2 LAST CDS_LOCATION R1356
J 0
(1575 3475);
DISPLAY 1.021277 (1575 3475);
DISPLAY INVISIBLE (1575 3475);
FORCEPROP 2 LAST $SEC 1
J 0
(1575 3475);
DISPLAY 0.680851 (1575 3475);
PAINT MONO (1575 3475);
DISPLAY INVISIBLE (1575 3475);
FORCEPROP 2 LAST CDS_SEC 1
J 0
(1575 3475);
DISPLAY 1.021277 (1575 3475);
DISPLAY INVISIBLE (1575 3475);
FORCEADD Q_RES..1
(1625 3450);
FORCEPROP 1 LAST PART_NUMBER CS41002FB09
J 0
(1450 3550);
DISPLAY 0.638298 (1450 3550);
DISPLAY INVISIBLE (1450 3550);
FORCEPROP 1 LAST MATERIAL CHIP
J 0
(1975 3450);
DISPLAY 0.638298 (1975 3450);
FORCEPROP 1 LAST VALUE 100K
J 2
(1850 3450);
DISPLAY 0.638298 (1850 3450);
FORCEPROP 1 LAST TOLERANCE 1%
J 0
(1875 3450);
DISPLAY 0.638298 (1875 3450);
FORCEPROP 1 LAST $LOCATION R1355
J 0
(1400 3450);
DISPLAY 0.638298 (1400 3450);
FORCEPROP 1 LASTPIN (1525 3450) $PN 1
J 0
(1537 3462);
DISPLAY 0.787234 (1537 3462);
FORCEPROP 1 LASTPIN (1725 3450) $PN 2
J 0
(1687 3462);
DISPLAY 0.787234 (1687 3462);
FORCEPROP 1 LAST PATH I54
J 0
(1575 3600);
DISPLAY 0.978723 (1575 3600);
PAINT WHITE (1575 3600);
DISPLAY INVISIBLE (1575 3600);
FORCEPROP 1 LAST PACK_TYPE 0402LF
J 0
(1450 3600);
DISPLAY 0.638298 (1450 3600);
DISPLAY INVISIBLE (1450 3600);
FORCEPROP 1 LAST WATTAGE 1/16W
J 2
(1900 3600);
DISPLAY 0.638298 (1900 3600);
DISPLAY INVISIBLE (1900 3600);
FORCEPROP 2 LAST CDS_LIB pure_quanta
J 0
(1625 3450);
PAINT MONO (1625 3450);
DISPLAY INVISIBLE (1625 3450);
FORCEPROP 2 LAST CDS_LOCATION R1355
J 0
(1575 3650);
DISPLAY 1.021277 (1575 3650);
DISPLAY INVISIBLE (1575 3650);
FORCEPROP 2 LAST $SEC 1
J 0
(1575 3650);
DISPLAY 0.680851 (1575 3650);
PAINT MONO (1575 3650);
DISPLAY INVISIBLE (1575 3650);
FORCEPROP 2 LAST CDS_SEC 1
J 0
(1575 3650);
DISPLAY 1.021277 (1575 3650);
DISPLAY INVISIBLE (1575 3650);
FORCEADD Q_RES..1
(1625 3600);
FORCEPROP 1 LAST PART_NUMBER CS41002FB09
J 0
(1450 3700);
DISPLAY 0.638298 (1450 3700);
DISPLAY INVISIBLE (1450 3700);
FORCEPROP 1 LAST MATERIAL CHIP
J 0
(1975 3600);
DISPLAY 0.638298 (1975 3600);
FORCEPROP 1 LAST TOLERANCE 1%
J 0
(1875 3600);
DISPLAY 0.638298 (1875 3600);
FORCEPROP 1 LAST VALUE 100K
J 2
(1850 3600);
DISPLAY 0.638298 (1850 3600);
FORCEPROP 1 LAST $LOCATION R1354
J 0
(1400 3600);
DISPLAY 0.638298 (1400 3600);
FORCEPROP 1 LASTPIN (1525 3600) $PN 1
J 0
(1537 3612);
DISPLAY 0.787234 (1537 3612);
FORCEPROP 1 LASTPIN (1725 3600) $PN 2
J 0
(1687 3612);
DISPLAY 0.787234 (1687 3612);
FORCEPROP 1 LAST PATH I55
J 0
(1575 3750);
DISPLAY 0.978723 (1575 3750);
PAINT WHITE (1575 3750);
DISPLAY INVISIBLE (1575 3750);
FORCEPROP 1 LAST PACK_TYPE 0402LF
J 0
(1450 3750);
DISPLAY 0.638298 (1450 3750);
DISPLAY INVISIBLE (1450 3750);
FORCEPROP 1 LAST WATTAGE 1/16W
J 2
(1900 3750);
DISPLAY 0.638298 (1900 3750);
DISPLAY INVISIBLE (1900 3750);
FORCEPROP 2 LAST CDS_LIB pure_quanta
J 0
(1625 3600);
PAINT MONO (1625 3600);
DISPLAY INVISIBLE (1625 3600);
FORCEPROP 2 LAST CDS_LOCATION R1354
J 0
(1575 3800);
DISPLAY 1.021277 (1575 3800);
DISPLAY INVISIBLE (1575 3800);
FORCEPROP 2 LAST $SEC 1
J 0
(1575 3800);
DISPLAY 0.680851 (1575 3800);
PAINT MONO (1575 3800);
DISPLAY INVISIBLE (1575 3800);
FORCEPROP 2 LAST CDS_SEC 1
J 0
(1575 3800);
DISPLAY 1.021277 (1575 3800);
DISPLAY INVISIBLE (1575 3800);
FORCEADD Q_RES..1
(1625 3750);
FORCEPROP 1 LAST PART_NUMBER CS41002FB09
J 0
(1450 3850);
DISPLAY 0.638298 (1450 3850);
DISPLAY INVISIBLE (1450 3850);
FORCEPROP 1 LAST MATERIAL CHIP
J 0
(1975 3750);
DISPLAY 0.638298 (1975 3750);
FORCEPROP 1 LAST TOLERANCE 1%
J 0
(1875 3750);
DISPLAY 0.638298 (1875 3750);
FORCEPROP 1 LAST VALUE 100K
J 2
(1850 3750);
DISPLAY 0.638298 (1850 3750);
FORCEPROP 1 LAST $LOCATION R1353
J 0
(1400 3750);
DISPLAY 0.638298 (1400 3750);
FORCEPROP 1 LASTPIN (1525 3750) $PN 1
J 0
(1537 3762);
DISPLAY 0.787234 (1537 3762);
FORCEPROP 1 LASTPIN (1725 3750) $PN 2
J 0
(1687 3762);
DISPLAY 0.787234 (1687 3762);
FORCEPROP 1 LAST PATH I56
J 0
(1575 3900);
DISPLAY 0.978723 (1575 3900);
PAINT WHITE (1575 3900);
DISPLAY INVISIBLE (1575 3900);
FORCEPROP 2 LAST CDS_LIB pure_quanta
J 0
(1625 3750);
PAINT MONO (1625 3750);
DISPLAY INVISIBLE (1625 3750);
FORCEPROP 1 LAST WATTAGE 1/16W
J 2
(1900 3900);
DISPLAY 0.638298 (1900 3900);
DISPLAY INVISIBLE (1900 3900);
FORCEPROP 1 LAST PACK_TYPE 0402LF
J 0
(1450 3900);
DISPLAY 0.638298 (1450 3900);
DISPLAY INVISIBLE (1450 3900);
FORCEPROP 2 LAST CDS_LOCATION R1353
J 0
(1575 3950);
DISPLAY 1.021277 (1575 3950);
DISPLAY INVISIBLE (1575 3950);
FORCEPROP 2 LAST $SEC 1
J 0
(1575 3950);
DISPLAY 0.680851 (1575 3950);
PAINT MONO (1575 3950);
DISPLAY INVISIBLE (1575 3950);
FORCEPROP 2 LAST CDS_SEC 1
J 0
(1575 3950);
DISPLAY 1.021277 (1575 3950);
DISPLAY INVISIBLE (1575 3950);
FORCEADD OFFPAGE..2
(1750 2225);
FORCEPROP 2 LAST $XR0 153 
J 0
(1939 2225);
DISPLAY 0.638298 (1939 2225);
PAINT MONO (1939 2225);
FORCEPROP 2 LAST PATH I57
J 0
(1950 2275);
DISPLAY 1.021277 (1950 2275);
DISPLAY INVISIBLE (1950 2275);
FORCEPROP 1 LAST COMMENT_BODY TRUE
J 0
(1705 2130);
DISPLAY 0.872340 (1705 2130);
PAINT GREEN (1705 2130);
DISPLAY INVISIBLE (1705 2130);
FORCEPROP 1 LAST OFFPAGE TRUE
J 0
(2075 2100);
DISPLAY 0.872340 (2075 2100);
PAINT GREEN (2075 2100);
DISPLAY INVISIBLE (2075 2100);
FORCEPROP 2 LAST CDS_LIB standard
J 0
(1750 2225);
PAINT MONO (1750 2225);
DISPLAY INVISIBLE (1750 2225);
FORCEADD OFFPAGE..2
(1750 2375);
FORCEPROP 2 LAST $XR0 153 
J 0
(1939 2375);
DISPLAY 0.638298 (1939 2375);
PAINT MONO (1939 2375);
FORCEPROP 2 LAST PATH I58
J 0
(1950 2425);
DISPLAY 1.021277 (1950 2425);
DISPLAY INVISIBLE (1950 2425);
FORCEPROP 1 LAST COMMENT_BODY TRUE
J 0
(1705 2280);
DISPLAY 0.872340 (1705 2280);
PAINT GREEN (1705 2280);
DISPLAY INVISIBLE (1705 2280);
FORCEPROP 1 LAST OFFPAGE TRUE
J 0
(2075 2250);
DISPLAY 0.872340 (2075 2250);
PAINT GREEN (2075 2250);
DISPLAY INVISIBLE (2075 2250);
FORCEPROP 2 LAST CDS_LIB standard
J 0
(1750 2375);
PAINT MONO (1750 2375);
DISPLAY INVISIBLE (1750 2375);
FORCEADD OFFPAGE..2
(1750 2525);
FORCEPROP 2 LAST $XR0 153 
J 0
(1939 2525);
DISPLAY 0.638298 (1939 2525);
PAINT MONO (1939 2525);
FORCEPROP 2 LAST PATH I59
J 0
(1950 2575);
DISPLAY 1.021277 (1950 2575);
DISPLAY INVISIBLE (1950 2575);
FORCEPROP 1 LAST COMMENT_BODY TRUE
J 0
(1705 2430);
DISPLAY 0.872340 (1705 2430);
PAINT GREEN (1705 2430);
DISPLAY INVISIBLE (1705 2430);
FORCEPROP 1 LAST OFFPAGE TRUE
J 0
(2075 2400);
DISPLAY 0.872340 (2075 2400);
PAINT GREEN (2075 2400);
DISPLAY INVISIBLE (2075 2400);
FORCEPROP 2 LAST CDS_LIB standard
J 0
(1750 2525);
PAINT MONO (1750 2525);
DISPLAY INVISIBLE (1750 2525);
FORCEADD UNIVERSAL_GND..1
(-3750 2200);
FORCEPROP 3 LASTPIN (-3750 2250) SIG_NAME GND\g
J 0
(-3740 2260);
DISPLAY 0.659574 (-3740 2260);
PAINT MONO (-3740 2260);
DISPLAY INVISIBLE (-3740 2260);
FORCEPROP 1 LAST PATH I6
J 0
(-3675 2200);
DISPLAY 0.872340 (-3675 2200);
PAINT AQUA (-3675 2200);
DISPLAY INVISIBLE (-3675 2200);
FORCEPROP 1 LAST HDL_POWER GND
J 1
(-3725 2125);
DISPLAY 0.872340 (-3725 2125);
PAINT GREEN (-3725 2125);
DISPLAY INVISIBLE (-3725 2125);
FORCEPROP 2 LAST CDS_LIB logical_power
J 0
(-3750 2200);
PAINT MONO (-3750 2200);
DISPLAY INVISIBLE (-3750 2200);
FORCEADD UNIVERSAL_GND..1
(2225 3050);
FORCEPROP 3 LASTPIN (2225 3100) SIG_NAME GND\g
J 0
(2235 3110);
DISPLAY 0.659574 (2235 3110);
PAINT MONO (2235 3110);
DISPLAY INVISIBLE (2235 3110);
FORCEPROP 1 LAST PATH I60
J 0
(2300 3050);
DISPLAY 0.872340 (2300 3050);
PAINT AQUA (2300 3050);
DISPLAY INVISIBLE (2300 3050);
FORCEPROP 2 LAST CDS_LIB logical_power
J 0
(2225 3050);
PAINT MONO (2225 3050);
DISPLAY INVISIBLE (2225 3050);
FORCEPROP 1 LAST HDL_POWER GND
J 1
(2250 2975);
DISPLAY 0.872340 (2250 2975);
PAINT GREEN (2250 2975);
DISPLAY INVISIBLE (2250 2975);
FORCEADD Q_RES..1
(50 4750);
FORCEPROP 1 LAST PART_NUMBER CS00002JB13
J 0
(0 4850);
DISPLAY 0.510638 (0 4850);
PAINT WHITE (0 4850);
DISPLAY INVISIBLE (0 4850);
FORCEPROP 1 LAST VALUE 0
J 2
(200 4750);
DISPLAY 0.638298 (200 4750);
FORCEPROP 1 LAST MATERIAL CHIP
J 0
(250 4750);
DISPLAY 0.638298 (250 4750);
FORCEPROP 1 LAST $LOCATION R1296
J 0
(-250 4750);
DISPLAY 0.702128 (-250 4750);
FORCEPROP 1 LAST PATH I61
J 0
(0 4900);
DISPLAY 0.978723 (0 4900);
PAINT WHITE (0 4900);
DISPLAY INVISIBLE (0 4900);
FORCEPROP 1 LAST TOLERANCE 5%
J 0
(50 4650);
DISPLAY 0.510638 (50 4650);
PAINT SKYBLUE (50 4650);
DISPLAY INVISIBLE (50 4650);
FORCEPROP 1 LAST WATTAGE 1/16W
J 2
(25 4600);
DISPLAY 0.510638 (25 4600);
PAINT SKYBLUE (25 4600);
DISPLAY INVISIBLE (25 4600);
FORCEPROP 1 LAST PACK_TYPE 0402LF
J 0
(300 4600);
DISPLAY 0.510638 (300 4600);
PAINT SKYBLUE (300 4600);
DISPLAY INVISIBLE (300 4600);
FORCEPROP 2 LAST CDS_LIB pure_quanta
J 0
(50 4750);
DISPLAY INVISIBLE (50 4750);
FORCEPROP 0 LAST CDS_LOCATION R1296
J 0
(125 4800);
DISPLAY 1.021277 (125 4800);
DISPLAY INVISIBLE (125 4800);
FORCEPROP 0 LAST $SEC 1
J 0
(125 4800);
DISPLAY INVISIBLE (125 4800);
FORCEPROP 0 LAST CDS_SEC 1
J 0
(125 4800);
DISPLAY INVISIBLE (125 4800);
FORCEPROP 1 LASTPIN (-50 4750) $PN 1
J 0
(-38 4762);
DISPLAY 0.808511 (-38 4762);
PAINT WHITE (-38 4762);
DISPLAY INVISIBLE (-38 4762);
FORCEPROP 1 LASTPIN (150 4750) $PN 2
J 0
(112 4762);
DISPLAY 0.808511 (112 4762);
PAINT WHITE (112 4762);
DISPLAY INVISIBLE (112 4762);
FORCEADD OFFPAGE..5
(300 3900);
FORCEPROP 2 LAST $XR2 240 
J 0
(-195 3900);
DISPLAY 0.638298 (-195 3900);
PAINT MONO (-195 3900);
FORCEPROP 2 LAST $XR1 160 
J 0
(-75 3900);
DISPLAY 0.638298 (-75 3900);
PAINT MONO (-75 3900);
FORCEPROP 2 LAST $XR0 154 
J 0
(45 3900);
DISPLAY 0.638298 (45 3900);
PAINT MONO (45 3900);
FORCEPROP 2 LAST PATH I62
J 0
(50 3950);
DISPLAY 1.021277 (50 3950);
DISPLAY INVISIBLE (50 3950);
FORCEPROP 1 LAST OFFPAGE TRUE
J 0
(625 3775);
DISPLAY 0.872340 (625 3775);
PAINT GREEN (625 3775);
DISPLAY INVISIBLE (625 3775);
FORCEPROP 1 LAST COMMENT_BODY TRUE
J 0
(400 3825);
DISPLAY 0.872340 (400 3825);
PAINT GREEN (400 3825);
DISPLAY INVISIBLE (400 3825);
FORCEPROP 2 LAST CDS_LIB standard
J 0
(300 3900);
PAINT MONO (300 3900);
DISPLAY INVISIBLE (300 3900);
FORCEADD OFFPAGE..5
(300 4050);
FORCEPROP 2 LAST $XR2 240 
J 0
(-195 4050);
DISPLAY 0.638298 (-195 4050);
PAINT MONO (-195 4050);
FORCEPROP 2 LAST $XR1 160 
J 0
(-75 4050);
DISPLAY 0.638298 (-75 4050);
PAINT MONO (-75 4050);
FORCEPROP 2 LAST $XR0 154 
J 0
(45 4050);
DISPLAY 0.638298 (45 4050);
PAINT MONO (45 4050);
FORCEPROP 2 LAST PATH I63
J 0
(50 4100);
DISPLAY 1.021277 (50 4100);
DISPLAY INVISIBLE (50 4100);
FORCEPROP 1 LAST OFFPAGE TRUE
J 0
(625 3925);
DISPLAY 0.872340 (625 3925);
PAINT GREEN (625 3925);
DISPLAY INVISIBLE (625 3925);
FORCEPROP 1 LAST COMMENT_BODY TRUE
J 0
(400 3975);
DISPLAY 0.872340 (400 3975);
PAINT GREEN (400 3975);
DISPLAY INVISIBLE (400 3975);
FORCEPROP 2 LAST CDS_LIB standard
J 0
(300 4050);
PAINT MONO (300 4050);
DISPLAY INVISIBLE (300 4050);
FORCEADD OFFPAGE..5
(300 4200);
FORCEPROP 2 LAST $XR2 240 
J 0
(-195 4200);
DISPLAY 0.638298 (-195 4200);
PAINT MONO (-195 4200);
FORCEPROP 2 LAST $XR1 160 
J 0
(-75 4200);
DISPLAY 0.638298 (-75 4200);
PAINT MONO (-75 4200);
FORCEPROP 2 LAST $XR0 154 
J 0
(45 4200);
DISPLAY 0.638298 (45 4200);
PAINT MONO (45 4200);
FORCEPROP 2 LAST PATH I64
J 0
(50 4250);
DISPLAY 1.021277 (50 4250);
DISPLAY INVISIBLE (50 4250);
FORCEPROP 1 LAST COMMENT_BODY TRUE
J 0
(400 4125);
DISPLAY 0.872340 (400 4125);
PAINT GREEN (400 4125);
DISPLAY INVISIBLE (400 4125);
FORCEPROP 1 LAST OFFPAGE TRUE
J 0
(625 4075);
DISPLAY 0.872340 (625 4075);
PAINT GREEN (625 4075);
DISPLAY INVISIBLE (625 4075);
FORCEPROP 2 LAST CDS_LIB standard
J 0
(300 4200);
PAINT MONO (300 4200);
DISPLAY INVISIBLE (300 4200);
FORCEADD Q_RES..1
(50 4900);
FORCEPROP 1 LAST PART_NUMBER CS00002JB13
J 0
(0 5000);
DISPLAY 0.510638 (0 5000);
PAINT WHITE (0 5000);
DISPLAY INVISIBLE (0 5000);
FORCEPROP 1 LAST MATERIAL CHIP
J 0
(250 4900);
DISPLAY 0.638298 (250 4900);
FORCEPROP 1 LAST VALUE 0
J 2
(200 4900);
DISPLAY 0.638298 (200 4900);
FORCEPROP 1 LAST $LOCATION R1295
J 0
(-250 4900);
DISPLAY 0.702128 (-250 4900);
FORCEPROP 1 LAST PATH I65
J 0
(0 5050);
DISPLAY 0.978723 (0 5050);
PAINT WHITE (0 5050);
DISPLAY INVISIBLE (0 5050);
FORCEPROP 1 LAST TOLERANCE 5%
J 0
(50 4800);
DISPLAY 0.510638 (50 4800);
PAINT SKYBLUE (50 4800);
DISPLAY INVISIBLE (50 4800);
FORCEPROP 1 LAST WATTAGE 1/16W
J 2
(25 4750);
DISPLAY 0.510638 (25 4750);
PAINT SKYBLUE (25 4750);
DISPLAY INVISIBLE (25 4750);
FORCEPROP 1 LAST PACK_TYPE 0402LF
J 0
(300 4750);
DISPLAY 0.510638 (300 4750);
PAINT SKYBLUE (300 4750);
DISPLAY INVISIBLE (300 4750);
FORCEPROP 2 LAST CDS_LIB pure_quanta
J 0
(50 4900);
DISPLAY INVISIBLE (50 4900);
FORCEPROP 0 LAST CDS_LOCATION R1295
J 0
(125 4950);
DISPLAY 1.021277 (125 4950);
DISPLAY INVISIBLE (125 4950);
FORCEPROP 0 LAST $SEC 1
J 0
(125 4950);
DISPLAY INVISIBLE (125 4950);
FORCEPROP 0 LAST CDS_SEC 1
J 0
(125 4950);
DISPLAY INVISIBLE (125 4950);
FORCEPROP 1 LASTPIN (-50 4900) $PN 1
J 0
(-38 4912);
DISPLAY 0.808511 (-38 4912);
PAINT WHITE (-38 4912);
DISPLAY INVISIBLE (-38 4912);
FORCEPROP 1 LASTPIN (150 4900) $PN 2
J 0
(112 4912);
DISPLAY 0.808511 (112 4912);
PAINT WHITE (112 4912);
DISPLAY INVISIBLE (112 4912);
FORCEADD Q_RES..1
(50 5050);
FORCEPROP 1 LAST PART_NUMBER CS00002JB13
J 0
(-75 5125);
DISPLAY 0.510638 (-75 5125);
DISPLAY INVISIBLE (-75 5125);
FORCEPROP 1 LAST VALUE 0
J 2
(200 5050);
DISPLAY 0.638298 (200 5050);
FORCEPROP 1 LAST MATERIAL CHIP
J 0
(250 5050);
DISPLAY 0.638298 (250 5050);
FORCEPROP 1 LAST $LOCATION R1294
J 0
(-250 5050);
DISPLAY 0.702128 (-250 5050);
FORCEPROP 1 LAST PATH I66
J 0
(0 5200);
DISPLAY 0.978723 (0 5200);
PAINT WHITE (0 5200);
DISPLAY INVISIBLE (0 5200);
FORCEPROP 1 LAST TOLERANCE 5%
J 0
(50 4950);
DISPLAY 0.510638 (50 4950);
PAINT SKYBLUE (50 4950);
DISPLAY INVISIBLE (50 4950);
FORCEPROP 2 LAST CDS_LIB pure_quanta
J 0
(50 5050);
DISPLAY INVISIBLE (50 5050);
FORCEPROP 1 LAST PACK_TYPE 0402LF
J 0
(300 4900);
DISPLAY 0.510638 (300 4900);
PAINT SKYBLUE (300 4900);
DISPLAY INVISIBLE (300 4900);
FORCEPROP 1 LAST WATTAGE 1/16W
J 2
(25 4900);
DISPLAY 0.510638 (25 4900);
PAINT SKYBLUE (25 4900);
DISPLAY INVISIBLE (25 4900);
FORCEPROP 0 LAST CDS_LOCATION R1294
J 0
(125 5100);
DISPLAY 1.021277 (125 5100);
DISPLAY INVISIBLE (125 5100);
FORCEPROP 0 LAST $SEC 1
J 0
(125 5100);
DISPLAY INVISIBLE (125 5100);
FORCEPROP 0 LAST CDS_SEC 1
J 0
(125 5100);
DISPLAY INVISIBLE (125 5100);
FORCEPROP 1 LASTPIN (-50 5050) $PN 1
J 0
(-38 5062);
DISPLAY 0.808511 (-38 5062);
PAINT WHITE (-38 5062);
DISPLAY INVISIBLE (-38 5062);
FORCEPROP 1 LASTPIN (150 5050) $PN 2
J 0
(112 5062);
DISPLAY 0.808511 (112 5062);
PAINT WHITE (112 5062);
DISPLAY INVISIBLE (112 5062);
FORCEADD Q_RES..1
(50 6175);
FORCEPROP 1 LAST PART_NUMBER CS02202FB02
J 0
(0 6275);
DISPLAY 0.510638 (0 6275);
PAINT WHITE (0 6275);
DISPLAY INVISIBLE (0 6275);
FORCEPROP 1 LAST VALUE 22
J 2
(0 6200);
DISPLAY 0.510638 (0 6200);
PAINT SKYBLUE (0 6200);
FORCEPROP 1 LAST MATERIAL CHIP
J 0
(125 6200);
DISPLAY 0.510638 (125 6200);
PAINT SKYBLUE (125 6200);
FORCEPROP 1 LAST $LOCATION R1293
J 0
(-250 6175);
DISPLAY 0.702128 (-250 6175);
PAINT YELLOW (-250 6175);
FORCEPROP 1 LAST PATH I67
J 0
(0 6325);
DISPLAY 0.978723 (0 6325);
PAINT WHITE (0 6325);
DISPLAY INVISIBLE (0 6325);
FORCEPROP 1 LAST WATTAGE 1/16W
J 2
(25 6025);
DISPLAY 0.510638 (25 6025);
PAINT SKYBLUE (25 6025);
DISPLAY INVISIBLE (25 6025);
FORCEPROP 1 LAST TOLERANCE 1%
J 0
(50 6075);
DISPLAY 0.510638 (50 6075);
PAINT SKYBLUE (50 6075);
DISPLAY INVISIBLE (50 6075);
FORCEPROP 1 LAST PACK_TYPE 0402LF
J 0
(300 6025);
DISPLAY 0.510638 (300 6025);
PAINT SKYBLUE (300 6025);
DISPLAY INVISIBLE (300 6025);
FORCEPROP 2 LAST CDS_LIB pure_quanta
J 0
(50 6175);
DISPLAY INVISIBLE (50 6175);
FORCEPROP 0 LAST CDS_LOCATION R1293
J 0
(125 6225);
DISPLAY 1.021277 (125 6225);
DISPLAY INVISIBLE (125 6225);
FORCEPROP 0 LAST $SEC 1
J 0
(125 6225);
DISPLAY INVISIBLE (125 6225);
FORCEPROP 0 LAST CDS_SEC 1
J 0
(125 6225);
DISPLAY INVISIBLE (125 6225);
FORCEPROP 1 LASTPIN (-50 6175) $PN 1
J 0
(-38 6187);
DISPLAY 0.808511 (-38 6187);
PAINT WHITE (-38 6187);
DISPLAY INVISIBLE (-38 6187);
FORCEPROP 1 LASTPIN (150 6175) $PN 2
J 0
(112 6187);
DISPLAY 0.808511 (112 6187);
PAINT WHITE (112 6187);
DISPLAY INVISIBLE (112 6187);
FORCEADD Q_RES..1
(50 6325);
FORCEPROP 1 LAST PART_NUMBER CS02202FB02
J 0
(0 6425);
DISPLAY 0.510638 (0 6425);
PAINT WHITE (0 6425);
DISPLAY INVISIBLE (0 6425);
FORCEPROP 1 LAST MATERIAL CHIP
J 0
(125 6350);
DISPLAY 0.510638 (125 6350);
PAINT SKYBLUE (125 6350);
FORCEPROP 1 LAST VALUE 22
J 2
(0 6350);
DISPLAY 0.510638 (0 6350);
PAINT SKYBLUE (0 6350);
FORCEPROP 1 LAST $LOCATION R1292
J 0
(-250 6325);
DISPLAY 0.702128 (-250 6325);
PAINT YELLOW (-250 6325);
FORCEPROP 1 LAST PATH I68
J 0
(0 6475);
DISPLAY 0.978723 (0 6475);
PAINT WHITE (0 6475);
DISPLAY INVISIBLE (0 6475);
FORCEPROP 1 LAST WATTAGE 1/16W
J 2
(25 6175);
DISPLAY 0.510638 (25 6175);
PAINT SKYBLUE (25 6175);
DISPLAY INVISIBLE (25 6175);
FORCEPROP 1 LAST TOLERANCE 1%
J 0
(50 6225);
DISPLAY 0.510638 (50 6225);
PAINT SKYBLUE (50 6225);
DISPLAY INVISIBLE (50 6225);
FORCEPROP 1 LAST PACK_TYPE 0402LF
J 0
(300 6175);
DISPLAY 0.510638 (300 6175);
PAINT SKYBLUE (300 6175);
DISPLAY INVISIBLE (300 6175);
FORCEPROP 2 LAST CDS_LIB pure_quanta
J 0
(50 6325);
DISPLAY INVISIBLE (50 6325);
FORCEPROP 0 LAST CDS_LOCATION R1292
J 0
(125 6375);
DISPLAY 1.021277 (125 6375);
DISPLAY INVISIBLE (125 6375);
FORCEPROP 0 LAST $SEC 1
J 0
(125 6375);
DISPLAY INVISIBLE (125 6375);
FORCEPROP 0 LAST CDS_SEC 1
J 0
(125 6375);
DISPLAY INVISIBLE (125 6375);
FORCEPROP 1 LASTPIN (-50 6325) $PN 1
J 0
(-38 6337);
DISPLAY 0.808511 (-38 6337);
PAINT WHITE (-38 6337);
DISPLAY INVISIBLE (-38 6337);
FORCEPROP 1 LASTPIN (150 6325) $PN 2
J 0
(112 6337);
DISPLAY 0.808511 (112 6337);
PAINT WHITE (112 6337);
DISPLAY INVISIBLE (112 6337);
FORCEADD Q_RES..1
(50 6475);
FORCEPROP 1 LAST PART_NUMBER CS02202FB02
J 0
(0 6575);
DISPLAY 0.510638 (0 6575);
PAINT WHITE (0 6575);
DISPLAY INVISIBLE (0 6575);
FORCEPROP 1 LAST VALUE 22
J 2
(0 6500);
DISPLAY 0.510638 (0 6500);
PAINT SKYBLUE (0 6500);
FORCEPROP 1 LAST MATERIAL CHIP
J 0
(125 6500);
DISPLAY 0.510638 (125 6500);
PAINT SKYBLUE (125 6500);
FORCEPROP 1 LAST $LOCATION R1291
J 0
(-250 6475);
DISPLAY 0.702128 (-250 6475);
PAINT YELLOW (-250 6475);
FORCEPROP 1 LAST PATH I69
J 0
(0 6625);
DISPLAY 0.978723 (0 6625);
PAINT WHITE (0 6625);
DISPLAY INVISIBLE (0 6625);
FORCEPROP 2 LAST CDS_LIB pure_quanta
J 0
(50 6475);
DISPLAY INVISIBLE (50 6475);
FORCEPROP 1 LAST PACK_TYPE 0402LF
J 0
(300 6325);
DISPLAY 0.510638 (300 6325);
PAINT SKYBLUE (300 6325);
DISPLAY INVISIBLE (300 6325);
FORCEPROP 1 LAST TOLERANCE 1%
J 0
(50 6375);
DISPLAY 0.510638 (50 6375);
PAINT SKYBLUE (50 6375);
DISPLAY INVISIBLE (50 6375);
FORCEPROP 1 LAST WATTAGE 1/16W
J 2
(25 6325);
DISPLAY 0.510638 (25 6325);
PAINT SKYBLUE (25 6325);
DISPLAY INVISIBLE (25 6325);
FORCEPROP 0 LAST CDS_LOCATION R1291
J 0
(125 6525);
DISPLAY 1.021277 (125 6525);
DISPLAY INVISIBLE (125 6525);
FORCEPROP 0 LAST $SEC 1
J 0
(125 6525);
DISPLAY INVISIBLE (125 6525);
FORCEPROP 0 LAST CDS_SEC 1
J 0
(125 6525);
DISPLAY INVISIBLE (125 6525);
FORCEPROP 1 LASTPIN (-50 6475) $PN 1
J 0
(-38 6487);
DISPLAY 0.808511 (-38 6487);
PAINT WHITE (-38 6487);
DISPLAY INVISIBLE (-38 6487);
FORCEPROP 1 LASTPIN (150 6475) $PN 2
J 0
(112 6487);
DISPLAY 0.808511 (112 6487);
PAINT WHITE (112 6487);
DISPLAY INVISIBLE (112 6487);
FORCEADD 74LVC1G126SE7..1
(-3375 2000);
FORCEPROP 1 LAST PART_NUMBER AL1G0126009
J 0
(-3269 1684);
DISPLAY 0.723404 (-3269 1684);
PAINT GREEN (-3269 1684);
DISPLAY INVISIBLE (-3269 1684);
FORCEPROP 2 LAST VALUE 74LVC1G126SE-7
J 0
(-3250 2125);
DISPLAY 0.638298 (-3250 2125);
FORCEPROP 2 LAST PART_TYPE SMLF
J 0
(-3250 2175);
DISPLAY 0.638298 (-3250 2175);
FORCEPROP 1 LAST MATERIAL IC
J 0
(-3269 1557);
DISPLAY 0.723404 (-3269 1557);
PAINT GREEN (-3269 1557);
FORCEPROP 1 LAST LOCATION U224
J 0
(-3269 1831);
DISPLAY 0.723404 (-3269 1831);
PAINT GREEN (-3269 1831);
FORCEPROP 0 LASTPIN (-3625 2050) $PN 2
J 2
(-3635 2060);
DISPLAY 0.680851 (-3635 2060);
PAINT MONO (-3635 2060);
FORCEPROP 0 LASTPIN (-3375 1750) $PN 3
R 1
J 2
(-3385 1740);
DISPLAY 0.680851 (-3385 1740);
PAINT MONO (-3385 1740);
FORCEPROP 0 LASTPIN (-3625 1950) $PN 1
J 2
(-3635 1960);
DISPLAY 0.680851 (-3635 1960);
PAINT MONO (-3635 1960);
FORCEPROP 0 LASTPIN (-3375 2250) $PN 5
R 1
J 0
(-3385 2260);
DISPLAY 0.680851 (-3385 2260);
PAINT MONO (-3385 2260);
FORCEPROP 0 LASTPIN (-3125 2000) $PN 4
J 0
(-3115 2010);
DISPLAY 0.680851 (-3115 2010);
PAINT MONO (-3115 2010);
FORCEPROP 1 LAST PATH I7
J 0
(-3375 2000);
DISPLAY 0.723404 (-3375 2000);
PAINT GREEN (-3375 2000);
DISPLAY INVISIBLE (-3375 2000);
FORCEPROP 1 LAST NEEDS_NO_SIZE TRUE
J 0
(-3375 2000);
DISPLAY 0.723404 (-3375 2000);
PAINT GREEN (-3375 2000);
DISPLAY INVISIBLE (-3375 2000);
FORCEPROP 1 LAST CDS_LMAN_SYM_OUTLINE -100,100,100,-100
J 0
(-3375 2000);
DISPLAY 0.468085 (-3375 2000);
PAINT GREEN (-3375 2000);
DISPLAY INVISIBLE (-3375 2000);
FORCEPROP 2 LAST CDS_LIB pure_quanta
J 0
(-3375 2000);
DISPLAY INVISIBLE (-3375 2000);
FORCEPROP 0 LAST $SEC 1
J 0
(-3250 2225);
DISPLAY 0.680851 (-3250 2225);
PAINT MONO (-3250 2225);
DISPLAY INVISIBLE (-3250 2225);
FORCEPROP 0 LAST CDS_SEC 1
J 0
(-3250 2225);
DISPLAY 1.021277 (-3250 2225);
DISPLAY INVISIBLE (-3250 2225);
FORCEADD OFFPAGE..4
(1200 4750);
FORCEPROP 2 LAST $XR2 160 
J 0
(1626 4750);
DISPLAY 0.638298 (1626 4750);
PAINT MONO (1626 4750);
FORCEPROP 2 LAST $XR1 240 
J 0
(1506 4750);
DISPLAY 0.638298 (1506 4750);
PAINT MONO (1506 4750);
FORCEPROP 2 LAST $XR0 154 
J 0
(1386 4750);
DISPLAY 0.638298 (1386 4750);
PAINT MONO (1386 4750);
FORCEPROP 2 LAST PATH I70
J 0
(1650 4800);
DISPLAY 1.021277 (1650 4800);
DISPLAY INVISIBLE (1650 4800);
FORCEPROP 2 LAST CDS_LIB standard
J 0
(1200 4750);
PAINT MONO (1200 4750);
DISPLAY INVISIBLE (1200 4750);
FORCEPROP 1 LAST OFFPAGE TRUE
J 0
(1525 4625);
DISPLAY 0.872340 (1525 4625);
PAINT GREEN (1525 4625);
DISPLAY INVISIBLE (1525 4625);
FORCEPROP 1 LAST COMMENT_BODY TRUE
J 0
(1175 4650);
DISPLAY 0.872340 (1175 4650);
PAINT GREEN (1175 4650);
DISPLAY INVISIBLE (1175 4650);
FORCEADD Q_RES..1
(1625 3900);
FORCEPROP 1 LAST PART_NUMBER CS41002FB09
J 0
(1450 4000);
DISPLAY 0.638298 (1450 4000);
DISPLAY INVISIBLE (1450 4000);
FORCEPROP 1 LAST VALUE 100K
J 2
(1850 3900);
DISPLAY 0.638298 (1850 3900);
FORCEPROP 1 LAST MATERIAL CHIP
J 0
(1975 3900);
DISPLAY 0.638298 (1975 3900);
FORCEPROP 1 LAST TOLERANCE 1%
J 0
(1875 3900);
DISPLAY 0.638298 (1875 3900);
FORCEPROP 1 LAST $LOCATION R1352
J 0
(1400 3900);
DISPLAY 0.638298 (1400 3900);
FORCEPROP 1 LASTPIN (1525 3900) $PN 1
J 0
(1537 3912);
DISPLAY 0.787234 (1537 3912);
FORCEPROP 1 LASTPIN (1725 3900) $PN 2
J 0
(1687 3912);
DISPLAY 0.787234 (1687 3912);
FORCEPROP 1 LAST PATH I71
J 0
(1575 4050);
DISPLAY 0.978723 (1575 4050);
PAINT WHITE (1575 4050);
DISPLAY INVISIBLE (1575 4050);
FORCEPROP 1 LAST PACK_TYPE 0402LF
J 0
(1450 4050);
DISPLAY 0.638298 (1450 4050);
DISPLAY INVISIBLE (1450 4050);
FORCEPROP 1 LAST WATTAGE 1/16W
J 2
(1900 4050);
DISPLAY 0.638298 (1900 4050);
DISPLAY INVISIBLE (1900 4050);
FORCEPROP 2 LAST CDS_LIB pure_quanta
J 0
(1625 3900);
PAINT MONO (1625 3900);
DISPLAY INVISIBLE (1625 3900);
FORCEPROP 2 LAST CDS_LOCATION R1352
J 0
(1575 4100);
DISPLAY 1.021277 (1575 4100);
DISPLAY INVISIBLE (1575 4100);
FORCEPROP 2 LAST $SEC 1
J 0
(1575 4100);
DISPLAY 0.680851 (1575 4100);
PAINT MONO (1575 4100);
DISPLAY INVISIBLE (1575 4100);
FORCEPROP 2 LAST CDS_SEC 1
J 0
(1575 4100);
DISPLAY 1.021277 (1575 4100);
DISPLAY INVISIBLE (1575 4100);
FORCEADD Q_RES..1
(1625 4050);
FORCEPROP 1 LAST PART_NUMBER CS41002FB09
J 0
(1450 4150);
DISPLAY 0.638298 (1450 4150);
DISPLAY INVISIBLE (1450 4150);
FORCEPROP 1 LAST TOLERANCE 1%
J 0
(1875 4050);
DISPLAY 0.638298 (1875 4050);
FORCEPROP 1 LAST MATERIAL CHIP
J 0
(1975 4050);
DISPLAY 0.638298 (1975 4050);
FORCEPROP 1 LAST VALUE 100K
J 2
(1850 4050);
DISPLAY 0.638298 (1850 4050);
FORCEPROP 1 LAST $LOCATION R1351
J 0
(1400 4050);
DISPLAY 0.638298 (1400 4050);
FORCEPROP 1 LASTPIN (1525 4050) $PN 1
J 0
(1537 4062);
DISPLAY 0.787234 (1537 4062);
FORCEPROP 1 LASTPIN (1725 4050) $PN 2
J 0
(1687 4062);
DISPLAY 0.787234 (1687 4062);
FORCEPROP 1 LAST PATH I72
J 0
(1575 4200);
DISPLAY 0.978723 (1575 4200);
PAINT WHITE (1575 4200);
DISPLAY INVISIBLE (1575 4200);
FORCEPROP 1 LAST PACK_TYPE 0402LF
J 0
(1450 4200);
DISPLAY 0.638298 (1450 4200);
DISPLAY INVISIBLE (1450 4200);
FORCEPROP 1 LAST WATTAGE 1/16W
J 2
(1900 4200);
DISPLAY 0.638298 (1900 4200);
DISPLAY INVISIBLE (1900 4200);
FORCEPROP 2 LAST CDS_LIB pure_quanta
J 0
(1625 4050);
PAINT MONO (1625 4050);
DISPLAY INVISIBLE (1625 4050);
FORCEPROP 2 LAST CDS_LOCATION R1351
J 0
(1575 4250);
DISPLAY 1.021277 (1575 4250);
DISPLAY INVISIBLE (1575 4250);
FORCEPROP 2 LAST $SEC 1
J 0
(1575 4250);
DISPLAY 0.680851 (1575 4250);
PAINT MONO (1575 4250);
DISPLAY INVISIBLE (1575 4250);
FORCEPROP 2 LAST CDS_SEC 1
J 0
(1575 4250);
DISPLAY 1.021277 (1575 4250);
DISPLAY INVISIBLE (1575 4250);
FORCEADD Q_RES..1
(1625 4200);
FORCEPROP 1 LAST PART_NUMBER CS41002FB09
J 0
(1475 4275);
DISPLAY 0.510638 (1475 4275);
DISPLAY INVISIBLE (1475 4275);
FORCEPROP 1 LAST VALUE 100K
J 2
(1850 4200);
DISPLAY 0.638298 (1850 4200);
FORCEPROP 1 LAST WATTAGE 1/16W
J 2
(1925 4325);
DISPLAY 0.510638 (1925 4325);
FORCEPROP 1 LAST MATERIAL CHIP
J 0
(1975 4200);
DISPLAY 0.638298 (1975 4200);
FORCEPROP 1 LAST TOLERANCE 1%
J 0
(1875 4200);
DISPLAY 0.638298 (1875 4200);
FORCEPROP 1 LAST PACK_TYPE 0402LF
J 0
(1475 4325);
DISPLAY 0.510638 (1475 4325);
FORCEPROP 1 LAST $LOCATION R1350
J 0
(1400 4200);
DISPLAY 0.638298 (1400 4200);
FORCEPROP 1 LASTPIN (1525 4200) $PN 1
J 0
(1537 4212);
DISPLAY 0.787234 (1537 4212);
FORCEPROP 1 LASTPIN (1725 4200) $PN 2
J 0
(1687 4212);
DISPLAY 0.787234 (1687 4212);
FORCEPROP 1 LAST PATH I73
J 0
(1575 4350);
DISPLAY 0.978723 (1575 4350);
PAINT WHITE (1575 4350);
DISPLAY INVISIBLE (1575 4350);
FORCEPROP 2 LAST CDS_LIB pure_quanta
J 0
(1625 4200);
PAINT MONO (1625 4200);
DISPLAY INVISIBLE (1625 4200);
FORCEPROP 2 LAST CDS_LOCATION R1350
J 0
(1575 4400);
DISPLAY 1.021277 (1575 4400);
DISPLAY INVISIBLE (1575 4400);
FORCEPROP 2 LAST $SEC 1
J 0
(1575 4400);
DISPLAY 0.680851 (1575 4400);
PAINT MONO (1575 4400);
DISPLAY INVISIBLE (1575 4400);
FORCEPROP 2 LAST CDS_SEC 1
J 0
(1575 4400);
DISPLAY 1.021277 (1575 4400);
DISPLAY INVISIBLE (1575 4400);
FORCEADD OFFPAGE..4
(1200 5050);
FORCEPROP 2 LAST $XR2 160 
J 0
(1626 5050);
DISPLAY 0.638298 (1626 5050);
PAINT MONO (1626 5050);
FORCEPROP 2 LAST $XR1 240 
J 0
(1506 5050);
DISPLAY 0.638298 (1506 5050);
PAINT MONO (1506 5050);
FORCEPROP 2 LAST $XR0 154 
J 0
(1386 5050);
DISPLAY 0.638298 (1386 5050);
PAINT MONO (1386 5050);
FORCEPROP 2 LAST PATH I74
J 0
(1650 5100);
DISPLAY 1.021277 (1650 5100);
DISPLAY INVISIBLE (1650 5100);
FORCEPROP 2 LAST CDS_LIB standard
J 0
(1200 5050);
PAINT MONO (1200 5050);
DISPLAY INVISIBLE (1200 5050);
FORCEPROP 1 LAST OFFPAGE TRUE
J 0
(1525 4925);
DISPLAY 0.872340 (1525 4925);
PAINT GREEN (1525 4925);
DISPLAY INVISIBLE (1525 4925);
FORCEPROP 1 LAST COMMENT_BODY TRUE
J 0
(1175 4950);
DISPLAY 0.872340 (1175 4950);
PAINT GREEN (1175 4950);
DISPLAY INVISIBLE (1175 4950);
FORCEADD OFFPAGE..4
(1200 4900);
FORCEPROP 2 LAST $XR2 160 
J 0
(1626 4900);
DISPLAY 0.638298 (1626 4900);
PAINT MONO (1626 4900);
FORCEPROP 2 LAST $XR1 240 
J 0
(1506 4900);
DISPLAY 0.638298 (1506 4900);
PAINT MONO (1506 4900);
FORCEPROP 2 LAST $XR0 154 
J 0
(1386 4900);
DISPLAY 0.638298 (1386 4900);
PAINT MONO (1386 4900);
FORCEPROP 2 LAST PATH I75
J 0
(1650 4950);
DISPLAY 1.021277 (1650 4950);
DISPLAY INVISIBLE (1650 4950);
FORCEPROP 2 LAST CDS_LIB standard
J 0
(1200 4900);
PAINT MONO (1200 4900);
DISPLAY INVISIBLE (1200 4900);
FORCEPROP 1 LAST OFFPAGE TRUE
J 0
(1525 4775);
DISPLAY 0.872340 (1525 4775);
PAINT GREEN (1525 4775);
DISPLAY INVISIBLE (1525 4775);
FORCEPROP 1 LAST COMMENT_BODY TRUE
J 0
(1175 4800);
DISPLAY 0.872340 (1175 4800);
PAINT GREEN (1175 4800);
DISPLAY INVISIBLE (1175 4800);
FORCEADD OFFPAGE..4
(2425 5200);
FORCEPROP 2 LAST $XR0 165 
J 0
(2611 5200);
DISPLAY 0.638298 (2611 5200);
PAINT MONO (2611 5200);
FORCEPROP 2 LAST PATH I76
J 0
(2625 5250);
DISPLAY 1.021277 (2625 5250);
DISPLAY INVISIBLE (2625 5250);
FORCEPROP 2 LAST CDS_LIB standard
J 0
(2425 5200);
PAINT MONO (2425 5200);
DISPLAY INVISIBLE (2425 5200);
FORCEPROP 1 LAST OFFPAGE TRUE
J 0
(2750 5075);
DISPLAY 0.872340 (2750 5075);
PAINT GREEN (2750 5075);
DISPLAY INVISIBLE (2750 5075);
FORCEPROP 1 LAST COMMENT_BODY TRUE
J 0
(2400 5100);
DISPLAY 0.872340 (2400 5100);
PAINT GREEN (2400 5100);
DISPLAY INVISIBLE (2400 5100);
FORCEADD OFFPAGE..2
(975 6175);
FORCEPROP 2 LAST $XR2 240 
J 0
(1404 6175);
DISPLAY 0.638298 (1404 6175);
PAINT MONO (1404 6175);
FORCEPROP 2 LAST $XR1 160 
J 0
(1284 6175);
DISPLAY 0.638298 (1284 6175);
PAINT MONO (1284 6175);
FORCEPROP 2 LAST $XR0 154 
J 0
(1164 6175);
DISPLAY 0.638298 (1164 6175);
PAINT MONO (1164 6175);
FORCEPROP 2 LAST PATH I77
J 0
(1425 6225);
DISPLAY 1.021277 (1425 6225);
DISPLAY INVISIBLE (1425 6225);
FORCEPROP 1 LAST OFFPAGE TRUE
J 0
(1300 6050);
DISPLAY 0.872340 (1300 6050);
PAINT GREEN (1300 6050);
DISPLAY INVISIBLE (1300 6050);
FORCEPROP 1 LAST COMMENT_BODY TRUE
J 0
(930 6080);
DISPLAY 0.872340 (930 6080);
PAINT GREEN (930 6080);
DISPLAY INVISIBLE (930 6080);
FORCEPROP 2 LAST CDS_LIB standard
J 0
(975 6175);
PAINT MONO (975 6175);
DISPLAY INVISIBLE (975 6175);
FORCEADD OFFPAGE..2
(975 6325);
FORCEPROP 2 LAST $XR2 240 
J 0
(1164 6289);
DISPLAY 0.638298 (1164 6289);
PAINT MONO (1164 6289);
FORCEPROP 2 LAST $XR1 160 
J 0
(1284 6325);
DISPLAY 0.638298 (1284 6325);
PAINT MONO (1284 6325);
FORCEPROP 2 LAST $XR0 154 
J 0
(1164 6325);
DISPLAY 0.638298 (1164 6325);
PAINT MONO (1164 6325);
FORCEPROP 2 LAST PATH I78
J 0
(1300 6375);
DISPLAY 1.021277 (1300 6375);
DISPLAY INVISIBLE (1300 6375);
FORCEPROP 1 LAST COMMENT_BODY TRUE
J 0
(930 6230);
DISPLAY 0.872340 (930 6230);
PAINT GREEN (930 6230);
DISPLAY INVISIBLE (930 6230);
FORCEPROP 1 LAST OFFPAGE TRUE
J 0
(1300 6200);
DISPLAY 0.872340 (1300 6200);
PAINT GREEN (1300 6200);
DISPLAY INVISIBLE (1300 6200);
FORCEPROP 2 LAST CDS_LIB standard
J 0
(975 6325);
PAINT MONO (975 6325);
DISPLAY INVISIBLE (975 6325);
FORCEADD OFFPAGE..2
(975 6475);
FORCEPROP 2 LAST $XR2 240 
J 0
(1164 6439);
DISPLAY 0.638298 (1164 6439);
PAINT MONO (1164 6439);
FORCEPROP 2 LAST $XR1 160 
J 0
(1284 6475);
DISPLAY 0.638298 (1284 6475);
PAINT MONO (1284 6475);
FORCEPROP 2 LAST $XR0 154 
J 0
(1164 6475);
DISPLAY 0.638298 (1164 6475);
PAINT MONO (1164 6475);
FORCEPROP 2 LAST PATH I79
J 0
(1300 6525);
DISPLAY 1.021277 (1300 6525);
DISPLAY INVISIBLE (1300 6525);
FORCEPROP 2 LAST CDS_LIB standard
J 0
(975 6475);
PAINT MONO (975 6475);
DISPLAY INVISIBLE (975 6475);
FORCEPROP 1 LAST OFFPAGE TRUE
J 0
(1300 6350);
DISPLAY 0.872340 (1300 6350);
PAINT GREEN (1300 6350);
DISPLAY INVISIBLE (1300 6350);
FORCEPROP 1 LAST COMMENT_BODY TRUE
J 0
(930 6380);
DISPLAY 0.872340 (930 6380);
PAINT GREEN (930 6380);
DISPLAY INVISIBLE (930 6380);
FORCEADD Q_CAP..1
R 2
(-3750 2425);
FORCEPROP 1 LAST PART_NUMBER CH4104K1B00
J 2
(-3800 2275);
DISPLAY 0.510638 (-3800 2275);
DISPLAY INVISIBLE (-3800 2275);
FORCEPROP 1 LAST TOLERANCE 10%
J 2
(-3800 2375);
DISPLAY 0.510638 (-3800 2375);
FORCEPROP 1 LAST PACK_TYPE 0402
J 2
(-3800 2225);
DISPLAY 0.510638 (-3800 2225);
FORCEPROP 1 LAST VOLTAGE 25V
J 2
(-3800 2425);
DISPLAY 0.510638 (-3800 2425);
FORCEPROP 1 LAST MATERIAL X7R
J 2
(-3800 2325);
DISPLAY 0.510638 (-3800 2325);
FORCEPROP 1 LAST VALUE 0.1UF
J 2
(-3800 2475);
DISPLAY 0.510638 (-3800 2475);
FORCEPROP 1 LAST $LOCATION C1840
J 2
(-3800 2525);
DISPLAY 0.978723 (-3800 2525);
FORCEPROP 1 LASTPIN (-3750 2525) $PN 1
J 2
(-3760 2505);
DISPLAY 0.787234 (-3760 2505);
FORCEPROP 1 LASTPIN (-3750 2325) $PN 2
J 2
(-3760 2305);
DISPLAY 0.787234 (-3760 2305);
FORCEPROP 1 LAST PATH I8
J 2
(-3800 2575);
DISPLAY 0.978723 (-3800 2575);
PAINT WHITE (-3800 2575);
DISPLAY INVISIBLE (-3800 2575);
FORCEPROP 2 LAST CDS_LIB pure_quanta
J 0
(-3750 2425);
PAINT MONO (-3750 2425);
DISPLAY INVISIBLE (-3750 2425);
FORCEPROP 2 LAST CDS_LOCATION C1840
J 0
(-3800 2625);
DISPLAY 1.021277 (-3800 2625);
DISPLAY INVISIBLE (-3800 2625);
FORCEPROP 2 LAST $SEC 1
J 0
(-3800 2625);
DISPLAY 0.680851 (-3800 2625);
PAINT MONO (-3800 2625);
DISPLAY INVISIBLE (-3800 2625);
FORCEPROP 2 LAST CDS_SEC 1
J 0
(-3800 2625);
DISPLAY 1.021277 (-3800 2625);
DISPLAY INVISIBLE (-3800 2625);
FORCEADD Q_RES..1
R 1
(1500 6450);
FORCEPROP 1 LAST PART_NUMBER CS00002JB13
J 0
(1550 6325);
DISPLAY 0.510638 (1550 6325);
DISPLAY INVISIBLE (1550 6325);
FORCEPROP 1 LAST MATERIAL CHIP
J 0
(1550 6375);
DISPLAY 0.638298 (1550 6375);
FORCEPROP 1 LAST VALUE 0
J 2
(1600 6450);
DISPLAY 0.638298 (1600 6450);
FORCEPROP 1 LAST $LOCATION R3237
J 0
(1550 6400);
DISPLAY 0.978723 (1550 6400);
FORCEPROP 1 LASTPIN (1500 6350) $PN 1
R 1
J 0
(1488 6362);
DISPLAY 0.787234 (1488 6362);
PAINT MONO (1488 6362);
FORCEPROP 1 LASTPIN (1500 6550) $PN 2
R 1
J 0
(1488 6512);
DISPLAY 0.787234 (1488 6512);
PAINT MONO (1488 6512);
FORCEPROP 1 LAST PATH I80
R 1
J 0
(1350 6400);
DISPLAY 0.978723 (1350 6400);
PAINT WHITE (1350 6400);
DISPLAY INVISIBLE (1350 6400);
FORCEPROP 2 LAST CDS_LIB pure_quanta
R 1
J 0
(1500 6450);
DISPLAY INVISIBLE (1500 6450);
FORCEPROP 1 LAST WATTAGE 1/16W
R 1
J 2
(1650 6425);
DISPLAY 0.510638 (1650 6425);
PAINT SKYBLUE (1650 6425);
DISPLAY INVISIBLE (1650 6425);
FORCEPROP 1 LAST PACK_TYPE 0402LF
R 1
J 0
(1650 6700);
DISPLAY 0.510638 (1650 6700);
PAINT SKYBLUE (1650 6700);
DISPLAY INVISIBLE (1650 6700);
FORCEPROP 1 LAST TOLERANCE 5%
R 1
J 0
(1600 6450);
DISPLAY 0.510638 (1600 6450);
PAINT SKYBLUE (1600 6450);
DISPLAY INVISIBLE (1600 6450);
FORCEPROP 0 LAST CDS_LOCATION R3237
R 1
J 0
(1600 6500);
DISPLAY 1.021277 (1600 6500);
DISPLAY INVISIBLE (1600 6500);
FORCEPROP 0 LAST $SEC 1
R 1
J 0
(1600 6500);
DISPLAY 0.680851 (1600 6500);
PAINT MONO (1600 6500);
DISPLAY INVISIBLE (1600 6500);
FORCEPROP 0 LAST CDS_SEC 1
R 1
J 0
(1600 6500);
DISPLAY 1.021277 (1600 6500);
DISPLAY INVISIBLE (1600 6500);
FORCEADD Q_RES..1
(1650 6625);
FORCEPROP 1 LAST PART_NUMBER CS02202FB02
J 0
(1550 6775);
DISPLAY 0.510638 (1550 6775);
PAINT WHITE (1550 6775);
DISPLAY INVISIBLE (1550 6775);
FORCEPROP 1 LAST MATERIAL EMPTY
J 0
(1650 6650);
DISPLAY 0.510638 (1650 6650);
PAINT RED (1650 6650);
FORCEPROP 1 LAST PACK_TYPE 0402LF
J 0
(1675 6725);
DISPLAY 0.510638 (1675 6725);
PAINT SKYBLUE (1675 6725);
FORCEPROP 1 LAST VALUE 22
J 2
(1600 6650);
DISPLAY 0.510638 (1600 6650);
PAINT SKYBLUE (1600 6650);
FORCEPROP 1 LAST WATTAGE 1/16W
J 2
(1650 6725);
DISPLAY 0.510638 (1650 6725);
PAINT SKYBLUE (1650 6725);
FORCEPROP 1 LAST $LOCATION R1290
J 0
(1350 6625);
DISPLAY 0.702128 (1350 6625);
PAINT YELLOW (1350 6625);
FORCEPROP 1 LAST PATH I81
J 0
(1600 6775);
DISPLAY 0.978723 (1600 6775);
PAINT WHITE (1600 6775);
DISPLAY INVISIBLE (1600 6775);
FORCEPROP 1 LAST TOLERANCE 1%
J 0
(1650 6525);
DISPLAY 0.510638 (1650 6525);
PAINT SKYBLUE (1650 6525);
DISPLAY INVISIBLE (1650 6525);
FORCEPROP 2 LAST CDS_LIB pure_quanta
J 0
(1650 6625);
DISPLAY INVISIBLE (1650 6625);
FORCEPROP 0 LAST CDS_LOCATION R1290
J 0
(1550 6800);
DISPLAY 1.021277 (1550 6800);
DISPLAY INVISIBLE (1550 6800);
FORCEPROP 0 LAST $SEC 1
J 0
(1725 6675);
DISPLAY INVISIBLE (1725 6675);
FORCEPROP 0 LAST CDS_SEC 1
J 0
(1725 6675);
DISPLAY INVISIBLE (1725 6675);
FORCEPROP 1 LASTPIN (1550 6625) $PN 1
J 0
(1562 6637);
DISPLAY 0.808511 (1562 6637);
PAINT WHITE (1562 6637);
DISPLAY INVISIBLE (1562 6637);
FORCEPROP 1 LASTPIN (1750 6625) $PN 2
J 0
(1712 6637);
DISPLAY 0.808511 (1712 6637);
PAINT WHITE (1712 6637);
DISPLAY INVISIBLE (1712 6637);
FORCEADD OFFPAGE..2
(2475 6625);
FORCEPROP 2 LAST $XR0 165 
J 0
(2664 6625);
DISPLAY 0.638298 (2664 6625);
PAINT MONO (2664 6625);
FORCEPROP 2 LAST PATH I82
J 0
(2675 6675);
DISPLAY 1.021277 (2675 6675);
DISPLAY INVISIBLE (2675 6675);
FORCEPROP 1 LAST COMMENT_BODY TRUE
J 0
(2430 6530);
DISPLAY 0.872340 (2430 6530);
PAINT GREEN (2430 6530);
DISPLAY INVISIBLE (2430 6530);
FORCEPROP 1 LAST OFFPAGE TRUE
J 0
(2800 6500);
DISPLAY 0.872340 (2800 6500);
PAINT GREEN (2800 6500);
DISPLAY INVISIBLE (2800 6500);
FORCEPROP 2 LAST CDS_LIB standard
J 0
(2475 6625);
PAINT MONO (2475 6625);
DISPLAY INVISIBLE (2475 6625);
FORCEADD Q_RES..1
(-1825 3725);
FORCEPROP 1 LAST PART_NUMBER CS04992FB07
J 0
(-1725 3700);
DISPLAY 0.404255 (-1725 3700);
DISPLAY INVISIBLE (-1725 3700);
FORCEPROP 1 LAST VALUE 49.9
J 2
(-1600 3725);
DISPLAY 0.510638 (-1600 3725);
FORCEPROP 1 LAST MATERIAL CHIP
J 0
(-1975 3700);
DISPLAY 0.404255 (-1975 3700);
FORCEPROP 1 LAST LOCATION R2473
J 0
(-2075 3725);
DISPLAY 0.808511 (-2075 3725);
FORCEPROP 1 LASTPIN (-1925 3725) $PN 1
J 0
(-1913 3737);
DISPLAY 0.787234 (-1913 3737);
PAINT MONO (-1913 3737);
FORCEPROP 1 LASTPIN (-1725 3725) $PN 2
J 0
(-1763 3737);
DISPLAY 0.787234 (-1763 3737);
PAINT MONO (-1763 3737);
FORCEPROP 2 LAST CDS_LIB pure_quanta
J 0
(-1825 3725);
DISPLAY INVISIBLE (-1825 3725);
FORCEPROP 1 LAST PATH I83
J 0
(-1875 3875);
DISPLAY 0.978723 (-1875 3875);
PAINT WHITE (-1875 3875);
DISPLAY INVISIBLE (-1875 3875);
FORCEPROP 1 LAST PACK_TYPE 0402LF
J 0
(-1525 3725);
DISPLAY 0.510638 (-1525 3725);
DISPLAY INVISIBLE (-1525 3725);
FORCEPROP 1 LAST TOLERANCE 1%
J 0
(-1600 3725);
DISPLAY 0.510638 (-1600 3725);
DISPLAY INVISIBLE (-1600 3725);
FORCEPROP 1 LAST WATTAGE 1/16W
J 2
(-1525 3675);
DISPLAY 0.404255 (-1525 3675);
DISPLAY INVISIBLE (-1525 3675);
FORCEPROP 0 LAST $SEC 1
J 0
(-2050 3775);
DISPLAY 0.680851 (-2050 3775);
PAINT MONO (-2050 3775);
DISPLAY INVISIBLE (-2050 3775);
FORCEPROP 0 LAST CDS_SEC 1
J 0
(-2050 3775);
DISPLAY 1.021277 (-2050 3775);
DISPLAY INVISIBLE (-2050 3775);
FORCEADD UNIVERSAL_POWER..1
(-3750 2725);
FORCEPROP 3 LASTPIN (-3750 2675) SIG_NAME P3V3_AUX\g
J 0
(-3740 2685);
DISPLAY 0.659574 (-3740 2685);
PAINT MONO (-3740 2685);
DISPLAY INVISIBLE (-3740 2685);
FORCEPROP 1 LAST HDL_POWER P3V3_AUX
J 1
(-3750 2775);
DISPLAY 0.872340 (-3750 2775);
PAINT GREEN (-3750 2775);
FORCEPROP 1 LAST PATH I9
J 0
(-3700 2750);
DISPLAY 0.872340 (-3700 2750);
PAINT AQUA (-3700 2750);
DISPLAY INVISIBLE (-3700 2750);
FORCEPROP 2 LAST CDS_LIB logical_power
J 0
(-3750 2725);
PAINT MONO (-3750 2725);
DISPLAY INVISIBLE (-3750 2725);
FORCEADD DNS..2
(-1875 3200);
PAINT RED (-1875 3200);
FORCEPROP 2 LAST CDS_LIB mstr_misc
J 0
(-1875 3200);
DISPLAY INVISIBLE (-1875 3200);
FORCEPROP 1 LAST COMMENT_BODY TRUE
R 1
J 0
(-1800 2975);
DISPLAY 0.872340 (-1800 2975);
PAINT GREEN (-1800 2975);
DISPLAY INVISIBLE (-1800 2975);
FORCEADD DNS..2
(1675 6625);
PAINT RED (1675 6625);
FORCEPROP 1 LAST COMMENT_BODY TRUE
R 1
J 0
(1750 6400);
DISPLAY 0.872340 (1750 6400);
PAINT GREEN (1750 6400);
DISPLAY INVISIBLE (1750 6400);
FORCEPROP 2 LAST CDS_LIB mstr_misc
J 0
(1675 6625);
DISPLAY INVISIBLE (1675 6625);
FORCEADD QUANTA_TITLE_BLOCK_C..1
(2775 900);
FORCEPROP 0 LAST CDS_CON_LAST_MODIFIED Fri Aug 25 14:02:16 2023
J 0
(890 915);
PAINT MONO (890 915);
DISPLAY INVISIBLE (890 915);
FORCEPROP 2 LAST CUSTOM_TXT_CDS <XR_PAGE_TITLE>
J 0
(-5115 6150);
DISPLAY 0.638298 (-5115 6150);
PAINT PINK (-5115 6150);
DISPLAY INVISIBLE (-5115 6150);
FORCEPROP 2 LAST CUSTOM_TXT_CDS <CON_LAST_MODIFIED>
J 0
(890 915);
DISPLAY 0.978723 (890 915);
FORCEPROP 2 LAST CUSTOM_TXT_CDS <Q_PROJ>
J 0
(393 1002);
DISPLAY 1.212766 (393 1002);
FORCEPROP 2 LAST CUSTOM_TXT_CDS <NAME_2>
J 0
(-400 950);
FORCEPROP 2 LAST CUSTOM_TXT_CDS <NAME_1>
J 0
(-400 1075);
FORCEPROP 2 LAST CUSTOM_TXT_CDS <Q_NUMBER>
J 0
(1372 1003);
DISPLAY 1.212766 (1372 1003);
FORCEPROP 2 LAST CUSTOM_TXT_CDS <Q_REV>
J 0
(2591 1003);
DISPLAY 1.212766 (2591 1003);
FORCEPROP 1 LAST CUSTOM_TXT_CDS <CON_PAGE_NUM> OF <CON_TOTAL_PAGES>
J 0
(2329 918);
DISPLAY 0.978723 (2329 918);
FORCEPROP 1 LAST Q_TITLE PCIE - SFF OCP3.0 (2/3)
J 0
(-6591 926);
DISPLAY 1.957447 (-6591 926);
PAINT GREEN (-6591 926);
FORCEPROP 1 LAST Q_DEPT 
J 1
(-988 949);
DISPLAY 1.957447 (-988 949);
PAINT GREEN (-988 949);
FORCEPROP 2 LAST CDS_XR_PAGE_TITLE CR-154 : @S9S_MB_2U_LIB.S9S_MB_2U(SCH_1):PAGE154
J 0
(-5115 6150);
DISPLAY 0.638298 (-5115 6150);
PAINT PINK (-5115 6150);
DISPLAY INVISIBLE (-5115 6150);
FORCEPROP 2 LAST PAGE_BORDER TRUE
J 0
(-5115 6150);
DISPLAY 0.638298 (-5115 6150);
PAINT PINK (-5115 6150);
DISPLAY INVISIBLE (-5115 6150);
FORCEPROP 1 LAST CDS_LMAN_SYM_OUTLINE -9475,6775,100,-125
J 0
(2775 900);
DISPLAY 0.468085 (2775 900);
PAINT GREEN (2775 900);
DISPLAY INVISIBLE (2775 900);
FORCEPROP 2 LAST CDS_LIB pure_quanta
J 0
(2775 900);
PAINT MONO (2775 900);
DISPLAY INVISIBLE (2775 900);
FORCEPROP 1 LAST COMMENT_BODY TRUE
J 0
(2787 887);
DISPLAY 0.978723 (2787 887);
PAINT GREEN (2787 887);
DISPLAY INVISIBLE (2787 887);
WIRE 16 -1 (-3750 2600)(-3750 2675);
WIRE 16 -1 (-3375 2600)(-3750 2600);
WIRE 16 -1 (-3750 2600)(-3750 2525);
WIRE 16 -1 (-2175 7125)(-2175 7225);
WIRE 16 -1 (-2375 7125)(-2175 7125);
WIRE 16 -1 (-2175 6675)(-2175 7125);
FORCEPROP 0 LAST VOLTAGE 3.3
J 0
(-2175 6900);
PAINT MONO (-2175 6900);
DISPLAY INVISIBLE (-2175 6900);
FORCEPROP 0 LAST CDS_PHYS_NET_NAME P3V3_AUX
J 0
(-2175 6947);
PAINT MONO (-2175 6947);
DISPLAY INVISIBLE (-2175 6947);
FORCEPROP 0 LAST $PHYS_NET_NAME P3V3_AUX
J 0
(-2175 6994);
PAINT MONO (-2175 6994);
DISPLAY INVISIBLE (-2175 6994);
WIRE 16 -1 (-2175 5700)(-2175 5800);
WIRE 16 -1 (-2375 5700)(-2175 5700);
WIRE 16 -1 (-2175 5250)(-2175 5700);
FORCEPROP 0 LAST VOLTAGE 3.3
J 0
(-2175 5475);
PAINT MONO (-2175 5475);
DISPLAY INVISIBLE (-2175 5475);
FORCEPROP 0 LAST CDS_PHYS_NET_NAME P3V3_AUX
J 0
(-2175 5522);
PAINT MONO (-2175 5522);
DISPLAY INVISIBLE (-2175 5522);
FORCEPROP 0 LAST $PHYS_NET_NAME P3V3_AUX
J 0
(-2175 5569);
PAINT MONO (-2175 5569);
DISPLAY INVISIBLE (-2175 5569);
WIRE 16 -1 (-3475 4275)(-3475 4325);
WIRE 16 -1 (-3050 4275)(-3475 4275);
WIRE 16 -1 (-3475 4275)(-3475 4250);
WIRE 16 -1 (2225 3275)(2225 3100);
WIRE 16 -1 (2225 3450)(2225 3275);
WIRE 16 -1 (1725 3275)(2225 3275);
WIRE 16 -1 (975 1650)(975 1600);
WIRE 16 -1 (725 1650)(975 1650);
WIRE 16 -1 (975 1725)(975 1650);
WIRE 16 -1 (-2375 6850)(-2375 6775);
WIRE 16 -1 (-2175 6125)(-2175 6050);
WIRE 16 -1 (-2175 6125)(-2025 6125);
FORCEPROP 0 LAST VOLTAGE 0
J 0
(-2100 6125);
PAINT MONO (-2100 6125);
DISPLAY INVISIBLE (-2100 6125);
FORCEPROP 0 LAST CDS_PHYS_NET_NAME GND
J 0
(-2100 6172);
PAINT MONO (-2100 6172);
DISPLAY INVISIBLE (-2100 6172);
WIRE 16 -1 (-2375 5425)(-2375 5350);
WIRE 16 -1 (-2175 4700)(-2175 4625);
WIRE 16 -1 (-2175 4700)(-2025 4700);
FORCEPROP 0 LAST VOLTAGE 0
J 0
(-2100 4700);
PAINT MONO (-2100 4700);
DISPLAY INVISIBLE (-2100 4700);
FORCEPROP 0 LAST CDS_PHYS_NET_NAME GND
J 0
(-2100 4747);
PAINT MONO (-2100 4747);
DISPLAY INVISIBLE (-2100 4747);
WIRE 16 -1 (-3475 4050)(-3475 3975);
WIRE 16 -1 (-3050 3475)(-3050 3400);
WIRE 16 -1 (-2525 1675)(-2525 1600);
WIRE 16 -1 (-3375 1750)(-3375 1675);
WIRE 16 -1 (-3750 2325)(-3750 2250);
WIRE 16 -1 (-1475 3425)(-1475 3350);
WIRE 16 2175 (-2150 3075)(-1550 3075);
WIRE 16 2175 (-1550 3825)(-1550 3075);
WIRE 16 2175 (-2150 3825)(-2150 3075);
WIRE 16 2175 (-2150 3825)(-1550 3825);
WIRE 16 -1 (-1225 6575)(-1000 6575);
WIRE 16 -1 (-1225 6425)(-1000 6425);
WIRE 16 -1 (-1000 6575)(-1000 6425);
WIRE 16 -1 (-1225 6275)(-1000 6275);
WIRE 16 -1 (-1000 6425)(-1000 6275);
WIRE 16 -1 (-1225 6125)(-1000 6125);
WIRE 16 -1 (-1000 6275)(-1000 6125);
WIRE 16 -1 (-1225 5150)(-1000 5150);
WIRE 16 -1 (-1000 6125)(-1000 5150);
WIRE 16 -1 (-1225 5000)(-1000 5000);
WIRE 16 -1 (-1000 5150)(-1000 5000);
WIRE 16 -1 (-1225 4850)(-1000 4850);
WIRE 16 -1 (-1000 5000)(-1000 4850);
WIRE 16 -1 (-1225 4700)(-1000 4700);
WIRE 16 -1 (-1000 4850)(-1000 4700);
WIRE 16 -1 (-1725 3725)(-1475 3725);
WIRE 16 -1 (-1475 3625)(-1475 3725);
WIRE 16 -1 (-1475 3725)(-1000 3725);
FORCEPROP 2 LAST SIG_NAME FB_BMC_ISOLATE
J 0
(-1385 3735);
DISPLAY 0.553191 (-1385 3735);
PAINT WHITE (-1385 3735);
WIRE 16 -1 (-1000 4700)(-1000 3725);
WIRE 16 -1 (-975 3200)(-1800 3200);
WIRE 16 -1 (-975 3725)(-975 3200);
WIRE 16 -1 (-1000 3725)(-975 3725);
WIRE 16 -1 (-975 3725)(-850 3725);
WIRE 16 -1 (-2800 3725)(-1925 3725);
FORCEPROP 2 LAST SIG_NAME FB_BMC_ISOLATE_R1
J 0
(-2635 3735);
DISPLAY 0.553191 (-2635 3735);
PAINT WHITE (-2635 3735);
WIRE 16 -1 (-3625 1950)(-4650 1950);
FORCEPROP 0 LAST CDS_PHYS_NET_NAME OCP_SFF_AUX_PWR_EN_R4
J 0
(-4285 1992);
PAINT MONO (-4285 1992);
DISPLAY INVISIBLE (-4285 1992);
FORCEPROP 2 LAST SIG_NAME OCP_SFF_AUX_PWR_EN_R4
J 0
(-4360 1960);
DISPLAY 0.680851 (-4360 1960);
PAINT WHITE (-4360 1960);
WIRE 16 2175 (-6325 1700)(-3675 1700);
WIRE 16 2175 (-3675 2000)(-3675 1700);
WIRE 16 2175 (-6325 2000)(-6325 1700);
WIRE 16 2175 (-6325 2000)(-3675 2000);
WIRE 16 -1 (-4850 1950)(-5650 1950);
FORCEPROP 0 LAST CDS_PHYS_NET_NAME OCP_SFF_AUX_PWR_EN
J 0
(-5285 1992);
PAINT MONO (-5285 1992);
DISPLAY INVISIBLE (-5285 1992);
FORCEPROP 2 LAST SIG_NAME OCP_SFF_AUX_PWR_EN
J 0
(-5635 1960);
DISPLAY 0.680851 (-5635 1960);
PAINT WHITE (-5635 1960);
WIRE 16 -1 (-4775 3675)(-5850 3675);
FORCEPROP 0 LAST CDS_PHYS_NET_NAME OCP_SFF_AUX_PWR_EN
J 0
(-5485 3717);
PAINT MONO (-5485 3717);
DISPLAY INVISIBLE (-5485 3717);
FORCEPROP 2 LAST SIG_NAME OCP_SFF_AUX_PWR_EN
J 0
(-5760 3685);
DISPLAY 0.680851 (-5760 3685);
PAINT WHITE (-5760 3685);
WIRE 16 -1 (-4575 3675)(-3300 3675);
FORCEPROP 2 LAST SIG_NAME OCP_SFF_AUX_PWR_EN_R1
J 0
(-4285 3685);
DISPLAY 0.680851 (-4285 3685);
PAINT WHITE (-4285 3685);
WIRE 16 -1 (-3150 3200)(-2000 3200);
FORCEPROP 2 LAST SIG_NAME FM_NCSI_OCP_V3_1_R_OE
J 0
(-2985 3210);
DISPLAY 0.553191 (-2985 3210);
PAINT WHITE (-2985 3210);
WIRE 16 -1 (-2975 5050)(-2025 5050);
FORCEPROP 2 LAST SIG_NAME NCSI_OCP_SFF_TX_EN
J 0
(-2935 5060);
DISPLAY 0.680851 (-2935 5060);
PAINT WHITE (-2935 5060);
WIRE 16 -1 (-2975 5200)(-2025 5200);
FORCEPROP 2 LAST SIG_NAME OCP_SFF_ISO2_RBT_ARB_OUT
J 0
(-2935 5210);
DISPLAY 0.680851 (-2935 5210);
PAINT WHITE (-2935 5210);
WIRE 16 -1 (925 6475)(150 6475);
FORCEPROP 2 LAST SIG_NAME RMII_OCP_BMC_CRSDV
J 0
(290 6485);
DISPLAY 0.680851 (290 6485);
PAINT WHITE (290 6485);
WIRE 16 2175 (1450 6275)(2100 6275);
WIRE 16 2175 (2100 6825)(2100 6275);
WIRE 16 2175 (1450 6825)(1450 6275);
WIRE 16 2175 (1450 6825)(2100 6825);
FORCEPROP 0 LAST M1 CO-LAYOUT
J 0
(1550 6850);
DISPLAY 1.021277 (1550 6850);
WIRE 16 -1 (-1225 5200)(1500 5200);
FORCEPROP 2 LAST SIG_NAME OCP_SFF_RBT_ARB_OUT
J 0
(-935 5210);
DISPLAY 0.680851 (-935 5210);
PAINT WHITE (-935 5210);
WIRE 16 -1 (2375 5200)(1500 5200);
WIRE 16 -1 (1500 6350)(1500 5200);
WIRE 16 -1 (1150 4900)(150 4900);
FORCEPROP 2 LAST SIG_NAME RMII_BMC_OCP_TXD_0
J 0
(440 4910);
DISPLAY 0.680851 (440 4910);
PAINT WHITE (440 4910);
WIRE 16 -1 (2425 6625)(1750 6625);
FORCEPROP 2 LAST SIG_NAME OCP_SFF_RBT_ARB_IN
J 0
(1815 6635);
DISPLAY 0.680851 (1815 6635);
PAINT WHITE (1815 6635);
WIRE 16 -1 (1500 6625)(-1225 6625);
FORCEPROP 0 LAST CDS_PHYS_NET_NAME OCP_SFF_RBT_ARB_IN_R
J 0
(-860 6667);
PAINT MONO (-860 6667);
DISPLAY INVISIBLE (-860 6667);
FORCEPROP 2 LAST SIG_NAME OCP_SFF_RBT_ARB_IN_R
J 0
(-935 6635);
DISPLAY 0.680851 (-935 6635);
PAINT WHITE (-935 6635);
WIRE 16 -1 (1500 6550)(1500 6625);
WIRE 16 -1 (1500 6625)(1550 6625);
WIRE 16 -1 (-1225 4750)(-50 4750);
FORCEPROP 2 LAST SIG_NAME NCSI_BMC_TXD1_R
J 0
(-935 4760);
DISPLAY 0.680851 (-935 4760);
PAINT WHITE (-935 4760);
WIRE 16 -1 (-3050 3975)(-3050 4275);
WIRE 16 -1 (-2175 5250)(-2025 5250);
FORCEPROP 0 LAST VOLTAGE 3.3
J 0
(-2100 5250);
PAINT MONO (-2100 5250);
DISPLAY INVISIBLE (-2100 5250);
FORCEPROP 0 LAST CDS_PHYS_NET_NAME P3V3_AUX
J 0
(-2100 5297);
PAINT MONO (-2100 5297);
DISPLAY INVISIBLE (-2100 5297);
FORCEPROP 0 LAST $PHYS_NET_NAME P3V3_AUX
J 0
(-2100 5344);
PAINT MONO (-2100 5344);
DISPLAY INVISIBLE (-2100 5344);
WIRE 16 -1 (-2375 5700)(-2375 5625);
WIRE 16 -1 (-2175 6675)(-2025 6675);
FORCEPROP 0 LAST VOLTAGE 3.3
J 0
(-2100 6675);
PAINT MONO (-2100 6675);
DISPLAY INVISIBLE (-2100 6675);
FORCEPROP 0 LAST CDS_PHYS_NET_NAME P3V3_AUX
J 0
(-2100 6722);
PAINT MONO (-2100 6722);
DISPLAY INVISIBLE (-2100 6722);
FORCEPROP 0 LAST $PHYS_NET_NAME P3V3_AUX
J 0
(-2100 6769);
PAINT MONO (-2100 6769);
DISPLAY INVISIBLE (-2100 6769);
WIRE 16 -1 (-2375 7125)(-2375 7050);
WIRE 16 -1 (725 1725)(725 1650);
WIRE 16 -1 (475 1650)(725 1650);
WIRE 16 -1 (475 1725)(475 1650);
WIRE 16 -1 (1725 3450)(2225 3450);
WIRE 16 -1 (1725 3600)(2225 3600);
WIRE 16 -1 (2225 3600)(2225 3450);
WIRE 16 -1 (1725 3750)(2225 3750);
WIRE 16 -1 (2225 3750)(2225 3600);
WIRE 16 -1 (1725 3900)(2225 3900);
WIRE 16 -1 (2225 3900)(2225 3750);
WIRE 16 -1 (1725 4050)(2225 4050);
WIRE 16 -1 (2225 4050)(2225 3900);
WIRE 16 -1 (2225 4200)(2225 4050);
WIRE 16 -1 (1725 4200)(2225 4200);
WIRE 16 -1 (-3375 2600)(-3375 2250);
WIRE 16 -1 (-4250 3775)(-3300 3775);
FORCEPROP 0 LAST CDS_PHYS_NET_NAME FM_OCP_SFF_PWR_GOOD
J 0
(-3885 3817);
PAINT MONO (-3885 3817);
DISPLAY INVISIBLE (-3885 3817);
FORCEPROP 2 LAST SIG_NAME FM_OCP_SFF_PWR_GOOD
J 0
(-4110 3785);
DISPLAY 0.680851 (-4110 3785);
PAINT WHITE (-4110 3785);
WIRE 16 -1 (-2975 6175)(-2025 6175);
FORCEPROP 2 LAST SIG_NAME NCSI_OCP_SFF_RXD1
J 0
(-2835 6185);
DISPLAY 0.680851 (-2835 6185);
PAINT WHITE (-2835 6185);
WIRE 16 -1 (-2975 4750)(-2025 4750);
FORCEPROP 2 LAST SIG_NAME NCSI_OCP_SFF_TXD1
J 0
(-2935 4760);
DISPLAY 0.680851 (-2935 4760);
PAINT WHITE (-2935 4760);
WIRE 16 -1 (-3125 2000)(-2525 2000);
FORCEPROP 2 LAST SIG_NAME RST_HP_OCP_SFF_R_N
J 0
(-3060 2010);
DISPLAY 0.553191 (-3060 2010);
PAINT WHITE (-3060 2010);
WIRE 16 -1 (-2300 2000)(-2525 2000);
WIRE 16 -1 (-2525 1875)(-2525 2000);
WIRE 16 -1 (-4575 2050)(-3625 2050);
FORCEPROP 0 LAST CDS_PHYS_NET_NAME RST_SMB_SWITCH_N
J 0
(-4210 2092);
PAINT MONO (-4210 2092);
DISPLAY INVISIBLE (-4210 2092);
FORCEPROP 2 LAST SIG_NAME RST_SMB_SWITCH_N
J 0
(-4435 2060);
DISPLAY 0.680851 (-4435 2060);
PAINT WHITE (-4435 2060);
WIRE 16 -1 (1150 5050)(150 5050);
FORCEPROP 2 LAST SIG_NAME RMII_BMC_OCP_TX_EN
J 0
(440 5060);
DISPLAY 0.680851 (440 5060);
PAINT WHITE (440 5060);
WIRE 16 -1 (1150 4750)(150 4750);
FORCEPROP 2 LAST SIG_NAME RMII_BMC_OCP_TXD_1
J 0
(440 4760);
DISPLAY 0.680851 (440 4760);
PAINT WHITE (440 4760);
WIRE 16 -1 (1525 3900)(350 3900);
FORCEPROP 2 LAST SIG_NAME RMII_OCP_BMC_RXD_1
J 0
(490 3910);
DISPLAY 0.680851 (490 3910);
PAINT WHITE (490 3910);
WIRE 16 -1 (1525 4200)(350 4200);
FORCEPROP 2 LAST SIG_NAME RMII_OCP_BMC_CRSDV
J 0
(490 4210);
DISPLAY 0.680851 (490 4210);
PAINT WHITE (490 4210);
WIRE 16 -1 (1525 4050)(350 4050);
FORCEPROP 2 LAST SIG_NAME RMII_OCP_BMC_RXD_0
J 0
(490 4060);
DISPLAY 0.680851 (490 4060);
PAINT WHITE (490 4060);
WIRE 16 -1 (925 6325)(150 6325);
FORCEPROP 2 LAST SIG_NAME RMII_OCP_BMC_RXD_0
J 0
(290 6335);
DISPLAY 0.680851 (290 6335);
PAINT WHITE (290 6335);
WIRE 16 -1 (925 6175)(150 6175);
FORCEPROP 2 LAST SIG_NAME RMII_OCP_BMC_RXD_1
J 0
(290 6185);
DISPLAY 0.680851 (290 6185);
PAINT WHITE (290 6185);
WIRE 16 -1 (-50 6475)(-1225 6475);
FORCEPROP 0 LAST CDS_PHYS_NET_NAME NCSI_BMC_CRS_DV_R
J 0
(-1160 6517);
PAINT MONO (-1160 6517);
DISPLAY INVISIBLE (-1160 6517);
FORCEPROP 2 LAST SIG_NAME NCSI_BMC_CRS_DV_R
J 0
(-935 6485);
DISPLAY 0.680851 (-935 6485);
PAINT WHITE (-935 6485);
WIRE 16 -1 (-1225 6325)(-50 6325);
FORCEPROP 0 LAST CDS_PHYS_NET_NAME NCSI_BMC_RXD0_R
J 0
(-1160 6367);
PAINT MONO (-1160 6367);
DISPLAY INVISIBLE (-1160 6367);
FORCEPROP 2 LAST SIG_NAME NCSI_BMC_RXD0_R
J 0
(-935 6335);
DISPLAY 0.680851 (-935 6335);
PAINT WHITE (-935 6335);
WIRE 16 -1 (-1225 6175)(-50 6175);
FORCEPROP 2 LAST SIG_NAME NCSI_BMC_RXD1_R
J 0
(-935 6185);
DISPLAY 0.680851 (-935 6185);
PAINT WHITE (-935 6185);
WIRE 16 -1 (-1225 4900)(-50 4900);
FORCEPROP 2 LAST SIG_NAME NCSI_BMC_TXD0_R
J 0
(-935 4910);
DISPLAY 0.680851 (-935 4910);
PAINT WHITE (-935 4910);
WIRE 16 -1 (-1225 5050)(-50 5050);
FORCEPROP 2 LAST SIG_NAME NCSI_BMC_TX_EN_R
J 0
(-935 5060);
DISPLAY 0.680851 (-935 5060);
PAINT WHITE (-935 5060);
WIRE 16 -1 (1700 2375)(725 2375);
FORCEPROP 0 LAST CDS_PHYS_NET_NAME OCP_SFF_ISO_BIF1_EN
J 0
(1090 2417);
PAINT MONO (1090 2417);
DISPLAY INVISIBLE (1090 2417);
FORCEPROP 2 LAST SIG_NAME OCP_SFF_ISO_BIF1_EN
J 0
(1015 2385);
DISPLAY 0.680851 (1015 2385);
PAINT WHITE (1015 2385);
WIRE 16 -1 (725 1925)(725 2375);
WIRE 16 -1 (1700 2225)(975 2225);
FORCEPROP 0 LAST CDS_PHYS_NET_NAME OCP_SFF_ISO_BIF2_EN
J 0
(1090 2267);
PAINT MONO (1090 2267);
DISPLAY INVISIBLE (1090 2267);
FORCEPROP 2 LAST SIG_NAME OCP_SFF_ISO_BIF2_EN
J 0
(1015 2235);
DISPLAY 0.680851 (1015 2235);
PAINT WHITE (1015 2235);
WIRE 16 -1 (975 1925)(975 2225);
WIRE 16 -1 (1525 3750)(350 3750);
FORCEPROP 2 LAST SIG_NAME RMII_BMC_OCP_TX_EN
J 0
(490 3760);
DISPLAY 0.680851 (490 3760);
PAINT WHITE (490 3760);
WIRE 16 -1 (1525 3450)(350 3450);
FORCEPROP 2 LAST SIG_NAME RMII_BMC_OCP_TXD_1
J 0
(490 3460);
DISPLAY 0.680851 (490 3460);
PAINT WHITE (490 3460);
WIRE 16 -1 (1525 3600)(350 3600);
FORCEPROP 2 LAST SIG_NAME RMII_BMC_OCP_TXD_0
J 0
(490 3610);
DISPLAY 0.680851 (490 3610);
PAINT WHITE (490 3610);
WIRE 16 -1 (1525 3275)(350 3275);
FORCEPROP 2 LAST SIG_NAME RMII_BMC_OCP_RX_ER
J 0
(490 3285);
DISPLAY 0.680851 (490 3285);
PAINT WHITE (490 3285);
WIRE 16 -1 (1700 2525)(475 2525);
FORCEPROP 0 LAST CDS_PHYS_NET_NAME OCP_SFF_ISO_BIF0_EN
J 0
(1090 2567);
PAINT MONO (1090 2567);
DISPLAY INVISIBLE (1090 2567);
FORCEPROP 2 LAST SIG_NAME OCP_SFF_ISO_BIF0_EN
J 0
(990 2535);
DISPLAY 0.680851 (990 2535);
PAINT WHITE (990 2535);
WIRE 16 -1 (475 1925)(475 2525);
WIRE 16 -1 (-1350 2000)(-2100 2000);
FORCEPROP 2 LAST SIG_NAME RST_SMB_OCP_SFF_N
J 0
(-1835 2010);
DISPLAY 0.553191 (-1835 2010);
PAINT WHITE (-1835 2010);
WIRE 16 -1 (-2975 6325)(-2025 6325);
FORCEPROP 0 LAST CDS_PHYS_NET_NAME NCSI_OCP_SFF_RXD0
J 0
(-2910 6367);
PAINT MONO (-2910 6367);
DISPLAY INVISIBLE (-2910 6367);
FORCEPROP 2 LAST SIG_NAME NCSI_OCP_SFF_RXD0
J 0
(-2835 6335);
DISPLAY 0.680851 (-2835 6335);
PAINT WHITE (-2835 6335);
WIRE 16 -1 (-2975 6625)(-2025 6625);
FORCEPROP 0 LAST CDS_PHYS_NET_NAME OCP_SFF_ISO1_RBT_ARB_IN
J 0
(-2610 6667);
PAINT MONO (-2610 6667);
DISPLAY INVISIBLE (-2610 6667);
FORCEPROP 2 LAST SIG_NAME OCP_SFF_ISO1_RBT_ARB_IN
J 0
(-2835 6635);
DISPLAY 0.680851 (-2835 6635);
PAINT WHITE (-2835 6635);
WIRE 16 -1 (-2025 6475)(-2975 6475);
FORCEPROP 0 LAST CDS_PHYS_NET_NAME NCSI_OCP_SFF_CRS_DV
J 0
(-2910 6517);
PAINT MONO (-2910 6517);
DISPLAY INVISIBLE (-2910 6517);
FORCEPROP 2 LAST SIG_NAME NCSI_OCP_SFF_CRS_DV
J 0
(-2835 6485);
DISPLAY 0.680851 (-2835 6485);
PAINT WHITE (-2835 6485);
WIRE 16 -1 (-2975 4900)(-2025 4900);
FORCEPROP 2 LAST SIG_NAME NCSI_OCP_SFF_TXD0
J 0
(-2935 4910);
DISPLAY 0.680851 (-2935 4910);
PAINT WHITE (-2935 4910);
DOT 1 (1500 6625);
DOT 1 (2225 4050);
DOT 1 (2225 3900);
DOT 1 (1500 5200);
DOT 1 (-1000 6425);
DOT 1 (-1000 6125);
DOT 1 (-1000 6275);
DOT 1 (-1000 5150);
DOT 1 (-1000 5000);
DOT 1 (-1000 4850);
DOT 1 (2225 3600);
DOT 1 (2225 3750);
DOT 1 (2225 3450);
DOT 1 (2225 3275);
DOT 1 (975 1650);
DOT 1 (725 1650);
DOT 1 (-1000 3725);
DOT 1 (-2175 7125);
DOT 1 (-2175 5700);
DOT 1 (-3475 4275);
DOT 1 (-2525 2000);
DOT 1 (-3750 2600);
DOT 1 (-1475 3725);
DOT 1 (-975 3725);
DOT 1 (-1000 4700);
FORCENOTE
20220803 POP R2473, DEPOP R2474
(-2700 3000) 0;
DISPLAY LEFT (-2700 3000);
DISPLAY 1.276596 (-2700 3000);
PAINT PINK (-2700 3000);
FORCENOTE
20220504 CHANGE NETNAME TO OCP_SFF_AUX_PWR_EN
(-6025 1650) 0;
DISPLAY LEFT (-6025 1650);
DISPLAY 1.063830 (-6025 1650);
PAINT WHITE (-6025 1650);
QUIT
